FILE_TYPE = MACRO_DRAWING;
SET COLOR_WIRE YELLOW;
SET COLOR_PROP ORANGE;
SET COLOR_DOT WHITE;
SET COLOR_ARC YELLOW;
SET COLOR_BODY GREEN;
SET COLOR_NOTE PURPLE;
SET PROP_DISPLAY VALUE;
SET PAGE_NUMBER P275;
FORCEADD UNIVERSAL_GND..1
(-10750 1150);
FORCEPROP 3 LASTPIN (-10750 1200) SIG_NAME GND\g
J 0
(-10740 1210);
DISPLAY 0.659574 (-10740 1210);
PAINT MONO (-10740 1210);
DISPLAY INVISIBLE (-10740 1210);
FORCEPROP 1 LAST HDL_POWER GND
J 1
(-10725 1075);
DISPLAY 0.872340 (-10725 1075);
PAINT GREEN (-10725 1075);
DISPLAY INVISIBLE (-10725 1075);
FORCEPROP 2 LAST CDS_LIB logical_power
J 0
(-10750 1150);
PAINT MONO (-10750 1150);
DISPLAY INVISIBLE (-10750 1150);
FORCEPROP 1 LAST PATH I1
J 0
(-10675 1150);
DISPLAY 0.872340 (-10675 1150);
PAINT AQUA (-10675 1150);
DISPLAY INVISIBLE (-10675 1150);
FORCEADD UNIVERSAL_GND..1
(-10250 2075);
FORCEPROP 3 LASTPIN (-10250 2125) SIG_NAME GND\g
J 0
(-10240 2135);
DISPLAY 0.659574 (-10240 2135);
PAINT MONO (-10240 2135);
DISPLAY INVISIBLE (-10240 2135);
FORCEPROP 1 LAST HDL_POWER GND
J 1
(-10225 2000);
DISPLAY 0.872340 (-10225 2000);
PAINT GREEN (-10225 2000);
DISPLAY INVISIBLE (-10225 2000);
FORCEPROP 2 LAST CDS_LIB logical_power
J 0
(-10250 2075);
PAINT MONO (-10250 2075);
DISPLAY INVISIBLE (-10250 2075);
FORCEPROP 1 LAST PATH I10
J 0
(-10175 2075);
DISPLAY 0.872340 (-10175 2075);
PAINT AQUA (-10175 2075);
DISPLAY INVISIBLE (-10175 2075);
FORCEADD Q_CAP..1
(-10250 2325);
FORCEPROP 1 LAST PART_NUMBER CH5222KEB01
J 0
(-10200 2150);
DISPLAY 0.617021 (-10200 2150);
PAINT BLUE (-10200 2150);
DISPLAY INVISIBLE (-10200 2150);
FORCEPROP 1 LAST MATERIAL X6S
J 0
(-10200 2250);
DISPLAY 0.617021 (-10200 2250);
PAINT SKYBLUE (-10200 2250);
FORCEPROP 1 LAST TOLERANCE 10%
J 0
(-10200 2300);
DISPLAY 0.617021 (-10200 2300);
PAINT SKYBLUE (-10200 2300);
FORCEPROP 1 LAST VALUE 2.2UF
J 0
(-10200 2400);
DISPLAY 0.617021 (-10200 2400);
PAINT SKYBLUE (-10200 2400);
FORCEPROP 1 LAST VOLTAGE 10V
J 0
(-10200 2350);
DISPLAY 0.617021 (-10200 2350);
PAINT SKYBLUE (-10200 2350);
FORCEPROP 1 LAST PACK_TYPE C0402
J 0
(-10200 2200);
DISPLAY 0.617021 (-10200 2200);
PAINT SKYBLUE (-10200 2200);
FORCEPROP 1 LAST LOCATION PC396
J 0
(-10200 2450);
DISPLAY 0.617021 (-10200 2450);
PAINT AQUA (-10200 2450);
FORCEPROP 1 LASTPIN (-10250 2425) $PN 1
J 0
(-10240 2405);
DISPLAY 0.617021 (-10240 2405);
PAINT MONO (-10240 2405);
FORCEPROP 1 LASTPIN (-10250 2225) $PN 2
J 0
(-10240 2205);
DISPLAY 0.617021 (-10240 2205);
PAINT MONO (-10240 2205);
FORCEPROP 2 LAST CDS_LIB pure_quanta
J 0
(-10250 2325);
DISPLAY INVISIBLE (-10250 2325);
FORCEPROP 1 LAST PATH I11
J 0
(-10200 2475);
DISPLAY 0.978723 (-10200 2475);
PAINT WHITE (-10200 2475);
DISPLAY INVISIBLE (-10200 2475);
FORCEPROP 1 LAST LOCATION PC396
J 0
(-10200 2500);
DISPLAY 1.021277 (-10200 2500);
PAINT AQUA (-10200 2500);
DISPLAY INVISIBLE (-10200 2500);
FORCEPROP 0 LAST $SEC 1
J 0
(-10200 2500);
DISPLAY 0.680851 (-10200 2500);
PAINT MONO (-10200 2500);
DISPLAY INVISIBLE (-10200 2500);
FORCEPROP 0 LAST CDS_SEC 1
J 0
(-10200 2500);
DISPLAY 1.021277 (-10200 2500);
DISPLAY INVISIBLE (-10200 2500);
FORCEADD Q_RES..2
(-10250 2725);
FORCEPROP 1 LAST PART_NUMBER CS-2202FB01
J 0
(-10210 2600);
DISPLAY 0.617021 (-10210 2600);
PAINT BLUE (-10210 2600);
DISPLAY INVISIBLE (-10210 2600);
FORCEPROP 1 LAST VALUE 2.2
J 0
(-10205 2800);
DISPLAY 0.617021 (-10205 2800);
PAINT SKYBLUE (-10205 2800);
FORCEPROP 1 LAST TOLERANCE 1%
J 0
(-10205 2750);
DISPLAY 0.617021 (-10205 2750);
PAINT SKYBLUE (-10205 2750);
FORCEPROP 1 LAST WATTAGE 1/16W
J 0
(-10210 2700);
DISPLAY 0.617021 (-10210 2700);
PAINT SKYBLUE (-10210 2700);
FORCEPROP 1 LAST MATERIAL CHIP
J 0
(-10210 2650);
DISPLAY 0.617021 (-10210 2650);
PAINT SKYBLUE (-10210 2650);
FORCEPROP 1 LAST PACK_TYPE 0402LF
J 0
(-10210 2550);
DISPLAY 0.617021 (-10210 2550);
PAINT SKYBLUE (-10210 2550);
FORCEPROP 1 LAST LOCATION PR227
J 0
(-10205 2850);
DISPLAY 0.617021 (-10205 2850);
PAINT AQUA (-10205 2850);
FORCEPROP 1 LASTPIN (-10250 2825) $PN 1
J 0
(-10245 2787);
DISPLAY 0.617021 (-10245 2787);
PAINT MONO (-10245 2787);
FORCEPROP 1 LASTPIN (-10250 2625) $PN 2
J 0
(-10245 2635);
DISPLAY 0.617021 (-10245 2635);
PAINT MONO (-10245 2635);
FORCEPROP 2 LAST CDS_LIB pure_quanta
J 0
(-10250 2725);
DISPLAY INVISIBLE (-10250 2725);
FORCEPROP 1 LAST PATH I12
J 0
(-10200 2900);
DISPLAY 0.978723 (-10200 2900);
PAINT WHITE (-10200 2900);
DISPLAY INVISIBLE (-10200 2900);
FORCEPROP 1 LAST LOCATION PR227
J 0
(-10200 2900);
DISPLAY 1.021277 (-10200 2900);
PAINT AQUA (-10200 2900);
DISPLAY INVISIBLE (-10200 2900);
FORCEPROP 0 LAST $SEC 1
J 0
(-10200 2900);
DISPLAY 0.680851 (-10200 2900);
PAINT MONO (-10200 2900);
DISPLAY INVISIBLE (-10200 2900);
FORCEPROP 0 LAST CDS_SEC 1
J 0
(-10200 2900);
DISPLAY 1.021277 (-10200 2900);
DISPLAY INVISIBLE (-10200 2900);
FORCEADD Q_RES..2
(-10775 3375);
FORCEPROP 1 LAST PART_NUMBER CS00002JB13
J 0
(-10735 3250);
DISPLAY 0.617021 (-10735 3250);
PAINT BLUE (-10735 3250);
DISPLAY INVISIBLE (-10735 3250);
FORCEPROP 1 LAST MATERIAL CHIP
J 0
(-10735 3300);
DISPLAY 0.617021 (-10735 3300);
PAINT SKYBLUE (-10735 3300);
FORCEPROP 1 LAST TOLERANCE 5%
J 0
(-10730 3400);
DISPLAY 0.617021 (-10730 3400);
PAINT SKYBLUE (-10730 3400);
FORCEPROP 1 LAST VALUE 0
J 0
(-10730 3450);
DISPLAY 0.617021 (-10730 3450);
PAINT SKYBLUE (-10730 3450);
FORCEPROP 1 LAST PACK_TYPE 0402LF
J 0
(-10735 3200);
DISPLAY 0.617021 (-10735 3200);
PAINT SKYBLUE (-10735 3200);
FORCEPROP 1 LAST WATTAGE 1/16W
J 0
(-10735 3350);
DISPLAY 0.617021 (-10735 3350);
PAINT SKYBLUE (-10735 3350);
FORCEPROP 1 LAST LOCATION PR702
J 0
(-10730 3500);
DISPLAY 0.617021 (-10730 3500);
PAINT AQUA (-10730 3500);
FORCEPROP 2 LAST CDS_LIB pure_quanta
J 0
(-10775 3375);
DISPLAY INVISIBLE (-10775 3375);
FORCEPROP 1 LAST PATH I13
J 0
(-10725 3550);
DISPLAY 0.978723 (-10725 3550);
PAINT WHITE (-10725 3550);
DISPLAY INVISIBLE (-10725 3550);
FORCEPROP 0 LAST $SEC 1
J 0
(-10725 3550);
DISPLAY INVISIBLE (-10725 3550);
FORCEPROP 0 LAST CDS_SEC 1
J 0
(-10725 3550);
DISPLAY INVISIBLE (-10725 3550);
FORCEPROP 1 LASTPIN (-10775 3475) $PN 1
J 0
(-10770 3437);
DISPLAY 0.787234 (-10770 3437);
PAINT MONO (-10770 3437);
DISPLAY INVISIBLE (-10770 3437);
FORCEPROP 1 LASTPIN (-10775 3275) $PN 2
J 0
(-10770 3285);
DISPLAY 0.787234 (-10770 3285);
PAINT MONO (-10770 3285);
DISPLAY INVISIBLE (-10770 3285);
FORCEADD VCC15..1
(-10775 3600);
FORCEPROP 3 LASTPIN (-10775 3550) SIG_NAME P5V\g
J 0
(-10765 3560);
DISPLAY 0.659574 (-10765 3560);
PAINT MONO (-10765 3560);
DISPLAY INVISIBLE (-10765 3560);
FORCEPROP 1 LAST HDL_POWER P5V
J 1
(-10775 3650);
DISPLAY 0.617021 (-10775 3650);
PAINT GREEN (-10775 3650);
FORCEPROP 2 LAST CDS_LIB logical_power
J 0
(-10775 3600);
DISPLAY INVISIBLE (-10775 3600);
FORCEPROP 1 LAST PATH I14
J 0
(-10725 3625);
DISPLAY 0.872340 (-10725 3625);
PAINT AQUA (-10725 3625);
DISPLAY INVISIBLE (-10725 3625);
FORCEADD UNIVERSAL_GND..1
(-9725 2475);
FORCEPROP 3 LASTPIN (-9725 2525) SIG_NAME GND\g
J 0
(-9715 2535);
DISPLAY 0.659574 (-9715 2535);
PAINT MONO (-9715 2535);
DISPLAY INVISIBLE (-9715 2535);
FORCEPROP 1 LAST HDL_POWER GND
J 1
(-9700 2400);
DISPLAY 0.872340 (-9700 2400);
PAINT GREEN (-9700 2400);
DISPLAY INVISIBLE (-9700 2400);
FORCEPROP 2 LAST CDS_LIB logical_power
J 0
(-9725 2475);
PAINT MONO (-9725 2475);
DISPLAY INVISIBLE (-9725 2475);
FORCEPROP 1 LAST PATH I15
J 0
(-9650 2475);
DISPLAY 0.872340 (-9650 2475);
PAINT AQUA (-9650 2475);
DISPLAY INVISIBLE (-9650 2475);
FORCEADD Q_CAP..1
(-9725 2725);
FORCEPROP 1 LAST PART_NUMBER CH5222KEB01
J 0
(-9675 2600);
DISPLAY 0.617021 (-9675 2600);
PAINT BLUE (-9675 2600);
DISPLAY INVISIBLE (-9675 2600);
FORCEPROP 1 LAST MATERIAL X6S
J 0
(-9675 2650);
DISPLAY 0.617021 (-9675 2650);
PAINT SKYBLUE (-9675 2650);
FORCEPROP 1 LAST TOLERANCE 10%
J 0
(-9675 2700);
DISPLAY 0.617021 (-9675 2700);
PAINT SKYBLUE (-9675 2700);
FORCEPROP 1 LAST VALUE 2.2UF
J 0
(-9675 2800);
DISPLAY 0.617021 (-9675 2800);
PAINT SKYBLUE (-9675 2800);
FORCEPROP 1 LAST VOLTAGE 10V
J 0
(-9675 2750);
DISPLAY 0.617021 (-9675 2750);
PAINT SKYBLUE (-9675 2750);
FORCEPROP 1 LAST PACK_TYPE C0402
J 0
(-9675 2550);
DISPLAY 0.617021 (-9675 2550);
PAINT SKYBLUE (-9675 2550);
FORCEPROP 1 LAST LOCATION PC1243_P1_2
J 0
(-9675 2850);
DISPLAY 0.617021 (-9675 2850);
PAINT AQUA (-9675 2850);
FORCEPROP 1 LASTPIN (-9725 2825) $PN 1
J 0
(-9715 2805);
DISPLAY 0.617021 (-9715 2805);
FORCEPROP 1 LASTPIN (-9725 2625) $PN 2
J 0
(-9715 2605);
DISPLAY 0.617021 (-9715 2605);
FORCEPROP 2 LAST CDS_LIB pure_quanta
J 0
(-9725 2725);
PAINT MONO (-9725 2725);
DISPLAY INVISIBLE (-9725 2725);
FORCEPROP 1 LAST PATH I16
J 0
(-9675 2875);
DISPLAY 0.978723 (-9675 2875);
PAINT WHITE (-9675 2875);
DISPLAY INVISIBLE (-9675 2875);
FORCEPROP 2 LAST $SEC 1
J 0
(-9675 2925);
DISPLAY 0.680851 (-9675 2925);
PAINT MONO (-9675 2925);
DISPLAY INVISIBLE (-9675 2925);
FORCEPROP 2 LAST CDS_SEC 1
J 0
(-9675 2925);
DISPLAY 1.021277 (-9675 2925);
DISPLAY INVISIBLE (-9675 2925);
FORCEADD Q_RES..2
(-10125 3375);
FORCEPROP 1 LAST PART_NUMBER CS00002JB13
J 0
(-10085 3250);
DISPLAY 0.617021 (-10085 3250);
PAINT BLUE (-10085 3250);
DISPLAY INVISIBLE (-10085 3250);
FORCEPROP 1 LAST PACK_TYPE 0402LF
J 0
(-10085 3200);
DISPLAY 0.617021 (-10085 3200);
PAINT SKYBLUE (-10085 3200);
FORCEPROP 1 LAST MATERIAL EMPTY
J 0
(-10085 3300);
DISPLAY 0.617021 (-10085 3300);
PAINT RED (-10085 3300);
FORCEPROP 1 LAST VALUE 0
J 0
(-10080 3450);
DISPLAY 0.617021 (-10080 3450);
PAINT SKYBLUE (-10080 3450);
FORCEPROP 1 LAST TOLERANCE 5%
J 0
(-10080 3400);
DISPLAY 0.617021 (-10080 3400);
PAINT SKYBLUE (-10080 3400);
FORCEPROP 1 LAST WATTAGE 1/16W
J 0
(-10085 3350);
DISPLAY 0.617021 (-10085 3350);
PAINT SKYBLUE (-10085 3350);
FORCEPROP 1 LAST LOCATION PR704
J 0
(-10080 3500);
DISPLAY 0.617021 (-10080 3500);
PAINT AQUA (-10080 3500);
FORCEPROP 2 LAST CDS_LIB pure_quanta
J 0
(-10125 3375);
DISPLAY INVISIBLE (-10125 3375);
FORCEPROP 1 LAST PATH I17
J 0
(-10075 3550);
DISPLAY 0.978723 (-10075 3550);
PAINT WHITE (-10075 3550);
DISPLAY INVISIBLE (-10075 3550);
FORCEPROP 0 LAST $SEC 1
J 0
(-10075 3550);
DISPLAY INVISIBLE (-10075 3550);
FORCEPROP 0 LAST CDS_SEC 1
J 0
(-10075 3550);
DISPLAY INVISIBLE (-10075 3550);
FORCEPROP 1 LASTPIN (-10125 3475) $PN 1
J 0
(-10120 3437);
DISPLAY 0.787234 (-10120 3437);
PAINT MONO (-10120 3437);
DISPLAY INVISIBLE (-10120 3437);
FORCEPROP 1 LASTPIN (-10125 3275) $PN 2
J 0
(-10120 3285);
DISPLAY 0.787234 (-10120 3285);
PAINT MONO (-10120 3285);
DISPLAY INVISIBLE (-10120 3285);
FORCEADD VCC15..1
(-10125 3600);
FORCEPROP 3 LASTPIN (-10125 3550) SIG_NAME P3V3\g
J 0
(-10115 3560);
DISPLAY 0.659574 (-10115 3560);
PAINT MONO (-10115 3560);
DISPLAY INVISIBLE (-10115 3560);
FORCEPROP 1 LAST HDL_POWER P3V3
J 1
(-10125 3650);
DISPLAY 0.617021 (-10125 3650);
PAINT GREEN (-10125 3650);
FORCEPROP 2 LAST CDS_LIB logical_power
J 0
(-10125 3600);
DISPLAY INVISIBLE (-10125 3600);
FORCEPROP 1 LAST PATH I18
J 0
(-10075 3625);
DISPLAY 0.872340 (-10075 3625);
PAINT AQUA (-10075 3625);
DISPLAY INVISIBLE (-10075 3625);
FORCEADD UNIVERSAL_GND..1
(-10725 3950);
FORCEPROP 3 LASTPIN (-10725 4000) SIG_NAME GND\g
J 0
(-10715 4010);
DISPLAY 0.659574 (-10715 4010);
PAINT MONO (-10715 4010);
DISPLAY INVISIBLE (-10715 4010);
FORCEPROP 1 LAST HDL_POWER GND
J 1
(-10700 3875);
DISPLAY 0.872340 (-10700 3875);
PAINT GREEN (-10700 3875);
DISPLAY INVISIBLE (-10700 3875);
FORCEPROP 2 LAST CDS_LIB logical_power
J 0
(-10725 3950);
PAINT MONO (-10725 3950);
DISPLAY INVISIBLE (-10725 3950);
FORCEPROP 1 LAST PATH I19
J 0
(-10650 3950);
DISPLAY 0.872340 (-10650 3950);
PAINT AQUA (-10650 3950);
DISPLAY INVISIBLE (-10650 3950);
FORCEADD Q_RES..2
R 2
(-10750 1375);
FORCEPROP 1 LAST PART_NUMBER CS28872FB01
J 2
(-10800 1250);
DISPLAY 0.617021 (-10800 1250);
PAINT BLUE (-10800 1250);
DISPLAY INVISIBLE (-10800 1250);
FORCEPROP 1 LAST WATTAGE 1/16W
J 2
(-10800 1350);
DISPLAY 0.617021 (-10800 1350);
PAINT SKYBLUE (-10800 1350);
FORCEPROP 1 LAST MATERIAL EMPTY
J 2
(-10800 1300);
DISPLAY 0.617021 (-10800 1300);
PAINT RED (-10800 1300);
FORCEPROP 1 LAST TOLERANCE 1%
J 2
(-10805 1400);
DISPLAY 0.617021 (-10805 1400);
PAINT SKYBLUE (-10805 1400);
FORCEPROP 1 LAST VALUE 8.87K
J 2
(-10805 1450);
DISPLAY 0.617021 (-10805 1450);
PAINT SKYBLUE (-10805 1450);
FORCEPROP 1 LAST PACK_TYPE 0402LF
J 2
(-10800 1200);
DISPLAY 0.617021 (-10800 1200);
PAINT SKYBLUE (-10800 1200);
FORCEPROP 1 LAST LOCATION PR224
J 2
(-10795 1500);
DISPLAY 0.617021 (-10795 1500);
PAINT AQUA (-10795 1500);
FORCEPROP 1 LASTPIN (-10750 1475) $PN 1
J 2
(-10755 1437);
DISPLAY 0.617021 (-10755 1437);
PAINT MONO (-10755 1437);
FORCEPROP 1 LASTPIN (-10750 1275) $PN 2
J 2
(-10755 1285);
DISPLAY 0.617021 (-10755 1285);
PAINT MONO (-10755 1285);
FORCEPROP 2 LAST CDS_LIB pure_quanta
J 2
(-10750 1375);
DISPLAY INVISIBLE (-10750 1375);
FORCEPROP 1 LAST PATH I2
J 2
(-10800 1550);
DISPLAY 0.978723 (-10800 1550);
PAINT WHITE (-10800 1550);
DISPLAY INVISIBLE (-10800 1550);
FORCEPROP 1 LAST LOCATION PR224
J 2
(-10800 1550);
DISPLAY 1.021277 (-10800 1550);
PAINT AQUA (-10800 1550);
DISPLAY INVISIBLE (-10800 1550);
FORCEPROP 0 LAST $SEC 1
J 2
(-10800 1550);
DISPLAY 0.680851 (-10800 1550);
PAINT MONO (-10800 1550);
DISPLAY INVISIBLE (-10800 1550);
FORCEPROP 0 LAST CDS_SEC 1
J 2
(-10800 1550);
DISPLAY 1.021277 (-10800 1550);
DISPLAY INVISIBLE (-10800 1550);
FORCEADD Q_RES..2
R 2
(-10725 4175);
FORCEPROP 1 LAST PART_NUMBER CS28872FB01
J 2
(-10775 4050);
DISPLAY 0.617021 (-10775 4050);
PAINT BLUE (-10775 4050);
DISPLAY INVISIBLE (-10775 4050);
FORCEPROP 1 LAST MATERIAL EMPTY
J 2
(-10775 4100);
DISPLAY 0.617021 (-10775 4100);
PAINT RED (-10775 4100);
FORCEPROP 1 LAST WATTAGE 1/16W
J 2
(-10775 4150);
DISPLAY 0.617021 (-10775 4150);
PAINT SKYBLUE (-10775 4150);
FORCEPROP 1 LAST TOLERANCE 1%
J 2
(-10780 4200);
DISPLAY 0.617021 (-10780 4200);
PAINT SKYBLUE (-10780 4200);
FORCEPROP 1 LAST VALUE 8.87K
J 2
(-10780 4250);
DISPLAY 0.617021 (-10780 4250);
PAINT SKYBLUE (-10780 4250);
FORCEPROP 1 LAST PACK_TYPE 0402LF
J 2
(-10775 4000);
DISPLAY 0.617021 (-10775 4000);
PAINT SKYBLUE (-10775 4000);
FORCEPROP 1 LAST LOCATION PR225
J 2
(-10770 4300);
DISPLAY 0.617021 (-10770 4300);
PAINT AQUA (-10770 4300);
FORCEPROP 1 LASTPIN (-10725 4275) $PN 1
J 2
(-10730 4237);
DISPLAY 0.617021 (-10730 4237);
PAINT MONO (-10730 4237);
FORCEPROP 1 LASTPIN (-10725 4075) $PN 2
J 2
(-10730 4085);
DISPLAY 0.617021 (-10730 4085);
PAINT MONO (-10730 4085);
FORCEPROP 2 LAST CDS_LIB pure_quanta
J 2
(-10725 4175);
DISPLAY INVISIBLE (-10725 4175);
FORCEPROP 1 LAST PATH I20
J 2
(-10775 4350);
DISPLAY 0.978723 (-10775 4350);
PAINT WHITE (-10775 4350);
DISPLAY INVISIBLE (-10775 4350);
FORCEPROP 1 LAST LOCATION PR225
J 2
(-10775 4350);
DISPLAY 1.021277 (-10775 4350);
PAINT AQUA (-10775 4350);
DISPLAY INVISIBLE (-10775 4350);
FORCEPROP 0 LAST $SEC 1
J 2
(-10775 4350);
DISPLAY 0.680851 (-10775 4350);
PAINT MONO (-10775 4350);
DISPLAY INVISIBLE (-10775 4350);
FORCEPROP 0 LAST CDS_SEC 1
J 2
(-10775 4350);
DISPLAY 1.021277 (-10775 4350);
DISPLAY INVISIBLE (-10775 4350);
FORCEADD UNIVERSAL_GND..1
(-10800 4400);
FORCEPROP 3 LASTPIN (-10800 4450) SIG_NAME GND\g
J 0
(-10790 4460);
DISPLAY 0.659574 (-10790 4460);
PAINT MONO (-10790 4460);
DISPLAY INVISIBLE (-10790 4460);
FORCEPROP 1 LAST HDL_POWER GND
J 1
(-10775 4325);
DISPLAY 0.872340 (-10775 4325);
PAINT GREEN (-10775 4325);
DISPLAY INVISIBLE (-10775 4325);
FORCEPROP 2 LAST CDS_LIB logical_power
J 0
(-10800 4400);
PAINT MONO (-10800 4400);
DISPLAY INVISIBLE (-10800 4400);
FORCEPROP 1 LAST PATH I21
J 0
(-10725 4400);
DISPLAY 0.872340 (-10725 4400);
PAINT AQUA (-10725 4400);
DISPLAY INVISIBLE (-10725 4400);
FORCEADD OFFPAGE..1
(-10250 4075);
FORCEPROP 2 LAST $XR0 284 
J 0
(-10502 4075);
DISPLAY 0.638298 (-10502 4075);
PAINT MONO (-10502 4075);
FORCEPROP 1 LAST COMMENT_BODY TRUE
J 0
(-10125 3975);
DISPLAY 0.872340 (-10125 3975);
PAINT GREEN (-10125 3975);
DISPLAY INVISIBLE (-10125 3975);
FORCEPROP 1 LAST OFFPAGE TRUE
J 0
(-9925 3950);
DISPLAY 0.872340 (-9925 3950);
PAINT GREEN (-9925 3950);
DISPLAY INVISIBLE (-9925 3950);
FORCEPROP 2 LAST CDS_LIB standard
J 0
(-10250 4075);
DISPLAY INVISIBLE (-10250 4075);
FORCEPROP 2 LAST PATH I22
J 0
(-10500 4125);
DISPLAY 1.021277 (-10500 4125);
DISPLAY INVISIBLE (-10500 4125);
FORCEADD OFFPAGE..5
(-10250 4175);
FORCEPROP 2 LAST $XR2 284 
J 0
(-10505 4211);
DISPLAY 0.638298 (-10505 4211);
PAINT MONO (-10505 4211);
FORCEPROP 2 LAST $XR1 290 
J 0
(-10505 4139);
DISPLAY 0.638298 (-10505 4139);
PAINT MONO (-10505 4139);
FORCEPROP 2 LAST $XR0 289 
J 0
(-10505 4175);
DISPLAY 0.638298 (-10505 4175);
PAINT MONO (-10505 4175);
FORCEPROP 1 LAST COMMENT_BODY TRUE
J 0
(-10150 4100);
DISPLAY 0.872340 (-10150 4100);
PAINT GREEN (-10150 4100);
DISPLAY INVISIBLE (-10150 4100);
FORCEPROP 1 LAST OFFPAGE TRUE
J 0
(-9925 4050);
DISPLAY 0.872340 (-9925 4050);
PAINT GREEN (-9925 4050);
DISPLAY INVISIBLE (-9925 4050);
FORCEPROP 2 LAST CDS_LIB standard
J 0
(-10250 4175);
DISPLAY INVISIBLE (-10250 4175);
FORCEPROP 2 LAST PATH I23
J 0
(-10500 4250);
DISPLAY 1.021277 (-10500 4250);
DISPLAY INVISIBLE (-10500 4250);
FORCEADD OFFPAGE..1
(-10250 4575);
FORCEPROP 2 LAST $XR6 290 
J 0
(-11222 4575);
DISPLAY 0.638298 (-11222 4575);
PAINT MONO (-11222 4575);
FORCEPROP 2 LAST $XR5 289 
J 0
(-11102 4575);
DISPLAY 0.638298 (-11102 4575);
PAINT MONO (-11102 4575);
FORCEPROP 2 LAST $XR4 288 
J 0
(-10982 4575);
DISPLAY 0.638298 (-10982 4575);
PAINT MONO (-10982 4575);
FORCEPROP 2 LAST $XR3 287 
J 0
(-10862 4575);
DISPLAY 0.638298 (-10862 4575);
PAINT MONO (-10862 4575);
FORCEPROP 2 LAST $XR2 286 
J 0
(-10742 4575);
DISPLAY 0.638298 (-10742 4575);
PAINT MONO (-10742 4575);
FORCEPROP 2 LAST $XR1 285 
J 0
(-10622 4575);
DISPLAY 0.638298 (-10622 4575);
PAINT MONO (-10622 4575);
FORCEPROP 2 LAST $XR0 284 
J 0
(-10502 4575);
DISPLAY 0.638298 (-10502 4575);
PAINT MONO (-10502 4575);
FORCEPROP 1 LAST COMMENT_BODY TRUE
J 0
(-10125 4475);
DISPLAY 0.872340 (-10125 4475);
PAINT GREEN (-10125 4475);
DISPLAY INVISIBLE (-10125 4475);
FORCEPROP 1 LAST OFFPAGE TRUE
J 0
(-9925 4450);
DISPLAY 0.872340 (-9925 4450);
PAINT GREEN (-9925 4450);
DISPLAY INVISIBLE (-9925 4450);
FORCEPROP 2 LAST CDS_LIB standard
J 0
(-10250 4575);
DISPLAY INVISIBLE (-10250 4575);
FORCEPROP 2 LAST PATH I24
J 0
(-10500 4625);
DISPLAY 1.021277 (-10500 4625);
DISPLAY INVISIBLE (-10500 4625);
FORCEADD OFFPAGE..5
(-10250 4675);
FORCEPROP 2 LAST $XR0 284 
J 0
(-10505 4675);
DISPLAY 0.638298 (-10505 4675);
PAINT MONO (-10505 4675);
FORCEPROP 1 LAST COMMENT_BODY TRUE
J 0
(-10150 4600);
DISPLAY 0.872340 (-10150 4600);
PAINT GREEN (-10150 4600);
DISPLAY INVISIBLE (-10150 4600);
FORCEPROP 1 LAST OFFPAGE TRUE
J 0
(-9925 4550);
DISPLAY 0.872340 (-9925 4550);
PAINT GREEN (-9925 4550);
DISPLAY INVISIBLE (-9925 4550);
FORCEPROP 2 LAST CDS_LIB standard
J 0
(-10250 4675);
DISPLAY INVISIBLE (-10250 4675);
FORCEPROP 2 LAST PATH I25
J 0
(-10500 4725);
DISPLAY 1.021277 (-10500 4725);
DISPLAY INVISIBLE (-10500 4725);
FORCEADD UNIVERSAL_GND..1
(-10250 4875);
FORCEPROP 3 LASTPIN (-10250 4925) SIG_NAME GND\g
J 0
(-10240 4935);
DISPLAY 0.659574 (-10240 4935);
PAINT MONO (-10240 4935);
DISPLAY INVISIBLE (-10240 4935);
FORCEPROP 1 LAST HDL_POWER GND
J 1
(-10225 4800);
DISPLAY 0.872340 (-10225 4800);
PAINT GREEN (-10225 4800);
DISPLAY INVISIBLE (-10225 4800);
FORCEPROP 2 LAST CDS_LIB logical_power
J 0
(-10250 4875);
PAINT MONO (-10250 4875);
DISPLAY INVISIBLE (-10250 4875);
FORCEPROP 1 LAST PATH I26
J 0
(-10175 4875);
DISPLAY 0.872340 (-10175 4875);
PAINT AQUA (-10175 4875);
DISPLAY INVISIBLE (-10175 4875);
FORCEADD Q_CAP..1
(-10250 5125);
FORCEPROP 1 LAST PART_NUMBER CH5222KEB01
J 0
(-10200 4950);
DISPLAY 0.617021 (-10200 4950);
PAINT BLUE (-10200 4950);
DISPLAY INVISIBLE (-10200 4950);
FORCEPROP 1 LAST MATERIAL X6S
J 0
(-10200 5050);
DISPLAY 0.617021 (-10200 5050);
PAINT SKYBLUE (-10200 5050);
FORCEPROP 1 LAST TOLERANCE 10%
J 0
(-10200 5100);
DISPLAY 0.617021 (-10200 5100);
PAINT SKYBLUE (-10200 5100);
FORCEPROP 1 LAST VALUE 2.2UF
J 0
(-10200 5200);
DISPLAY 0.617021 (-10200 5200);
PAINT SKYBLUE (-10200 5200);
FORCEPROP 1 LAST VOLTAGE 10V
J 0
(-10200 5150);
DISPLAY 0.617021 (-10200 5150);
PAINT SKYBLUE (-10200 5150);
FORCEPROP 1 LAST PACK_TYPE C0402
J 0
(-10200 5000);
DISPLAY 0.617021 (-10200 5000);
PAINT SKYBLUE (-10200 5000);
FORCEPROP 1 LAST LOCATION PC395
J 0
(-10200 5250);
DISPLAY 0.617021 (-10200 5250);
PAINT AQUA (-10200 5250);
FORCEPROP 1 LASTPIN (-10250 5225) $PN 1
J 0
(-10240 5205);
DISPLAY 0.617021 (-10240 5205);
PAINT MONO (-10240 5205);
FORCEPROP 1 LASTPIN (-10250 5025) $PN 2
J 0
(-10240 5005);
DISPLAY 0.617021 (-10240 5005);
PAINT MONO (-10240 5005);
FORCEPROP 2 LAST CDS_LIB pure_quanta
J 0
(-10250 5125);
DISPLAY INVISIBLE (-10250 5125);
FORCEPROP 1 LAST PATH I27
J 0
(-10200 5275);
DISPLAY 0.978723 (-10200 5275);
PAINT WHITE (-10200 5275);
DISPLAY INVISIBLE (-10200 5275);
FORCEPROP 1 LAST LOCATION PC395
J 0
(-10200 5300);
DISPLAY 1.021277 (-10200 5300);
PAINT AQUA (-10200 5300);
DISPLAY INVISIBLE (-10200 5300);
FORCEPROP 0 LAST $SEC 1
J 0
(-10200 5300);
DISPLAY 0.680851 (-10200 5300);
PAINT MONO (-10200 5300);
DISPLAY INVISIBLE (-10200 5300);
FORCEPROP 0 LAST CDS_SEC 1
J 0
(-10200 5300);
DISPLAY 1.021277 (-10200 5300);
DISPLAY INVISIBLE (-10200 5300);
FORCEADD Q_RES..2
(-10250 5525);
FORCEPROP 1 LAST PART_NUMBER CS-2202FB01
J 0
(-10210 5400);
DISPLAY 0.617021 (-10210 5400);
PAINT BLUE (-10210 5400);
DISPLAY INVISIBLE (-10210 5400);
FORCEPROP 1 LAST WATTAGE 1/16W
J 0
(-10210 5500);
DISPLAY 0.617021 (-10210 5500);
PAINT SKYBLUE (-10210 5500);
FORCEPROP 1 LAST MATERIAL CHIP
J 0
(-10210 5450);
DISPLAY 0.617021 (-10210 5450);
PAINT SKYBLUE (-10210 5450);
FORCEPROP 1 LAST TOLERANCE 1%
J 0
(-10205 5550);
DISPLAY 0.617021 (-10205 5550);
PAINT SKYBLUE (-10205 5550);
FORCEPROP 1 LAST VALUE 2.2
J 0
(-10205 5600);
DISPLAY 0.617021 (-10205 5600);
PAINT SKYBLUE (-10205 5600);
FORCEPROP 1 LAST PACK_TYPE 0402LF
J 0
(-10210 5350);
DISPLAY 0.617021 (-10210 5350);
PAINT SKYBLUE (-10210 5350);
FORCEPROP 1 LAST LOCATION PR226
J 0
(-10205 5650);
DISPLAY 0.617021 (-10205 5650);
PAINT AQUA (-10205 5650);
FORCEPROP 1 LASTPIN (-10250 5625) $PN 1
J 0
(-10245 5587);
DISPLAY 0.617021 (-10245 5587);
PAINT MONO (-10245 5587);
FORCEPROP 1 LASTPIN (-10250 5425) $PN 2
J 0
(-10245 5435);
DISPLAY 0.617021 (-10245 5435);
PAINT MONO (-10245 5435);
FORCEPROP 2 LAST CDS_LIB pure_quanta
J 0
(-10250 5525);
DISPLAY INVISIBLE (-10250 5525);
FORCEPROP 1 LAST PATH I28
J 0
(-10200 5700);
DISPLAY 0.978723 (-10200 5700);
PAINT WHITE (-10200 5700);
DISPLAY INVISIBLE (-10200 5700);
FORCEPROP 1 LAST LOCATION PR226
J 0
(-10200 5700);
DISPLAY 1.021277 (-10200 5700);
PAINT AQUA (-10200 5700);
DISPLAY INVISIBLE (-10200 5700);
FORCEPROP 0 LAST $SEC 1
J 0
(-10200 5700);
DISPLAY 0.680851 (-10200 5700);
PAINT MONO (-10200 5700);
DISPLAY INVISIBLE (-10200 5700);
FORCEPROP 0 LAST CDS_SEC 1
J 0
(-10200 5700);
DISPLAY 1.021277 (-10200 5700);
DISPLAY INVISIBLE (-10200 5700);
FORCEADD Q_CAP..2
(-9975 4475);
FORCEPROP 1 LAST PART_NUMBER CH4104K1B00
J 1
(-9750 4525);
DISPLAY 0.617021 (-9750 4525);
PAINT BLUE (-9750 4525);
DISPLAY INVISIBLE (-9750 4525);
FORCEPROP 1 LAST TOLERANCE 10%
J 2
(-9375 4525);
DISPLAY 0.617021 (-9375 4525);
PAINT SKYBLUE (-9375 4525);
FORCEPROP 1 LAST PACK_TYPE 0402
J 1
(-9550 4475);
DISPLAY 0.617021 (-9550 4475);
PAINT SKYBLUE (-9550 4475);
FORCEPROP 1 LAST MATERIAL X7R
J 0
(-9575 4525);
DISPLAY 0.617021 (-9575 4525);
PAINT SKYBLUE (-9575 4525);
FORCEPROP 1 LAST VOLTAGE 25V
J 0
(-9725 4475);
DISPLAY 0.617021 (-9725 4475);
PAINT SKYBLUE (-9725 4475);
FORCEPROP 1 LAST VALUE 0.1UF
J 2
(-9750 4475);
DISPLAY 0.617021 (-9750 4475);
PAINT SKYBLUE (-9750 4475);
FORCEPROP 1 LAST LOCATION PC1367
J 1
(-10175 4475);
DISPLAY 0.617021 (-10175 4475);
PAINT AQUA (-10175 4475);
FORCEPROP 1 LASTPIN (-10075 4475) $PN 1
J 0
(-10085 4490);
DISPLAY 0.617021 (-10085 4490);
FORCEPROP 1 LASTPIN (-9875 4475) $PN 2
J 0
(-9890 4490);
DISPLAY 0.617021 (-9890 4490);
FORCEPROP 2 LAST CDS_LIB pure_quanta
J 0
(-9975 4475);
PAINT MONO (-9975 4475);
DISPLAY INVISIBLE (-9975 4475);
FORCEPROP 1 LAST PATH I29
J 0
(-9975 4675);
DISPLAY 0.978723 (-9975 4675);
PAINT WHITE (-9975 4675);
DISPLAY INVISIBLE (-9975 4675);
FORCEPROP 2 LAST $SEC 1
J 0
(-9975 4725);
DISPLAY 0.680851 (-9975 4725);
PAINT MONO (-9975 4725);
DISPLAY INVISIBLE (-9975 4725);
FORCEPROP 2 LAST CDS_SEC 1
J 0
(-9975 4725);
DISPLAY 1.021277 (-9975 4725);
DISPLAY INVISIBLE (-9975 4725);
FORCEADD UNIVERSAL_GND..1
(-10800 1600);
FORCEPROP 3 LASTPIN (-10800 1650) SIG_NAME GND\g
J 0
(-10790 1660);
DISPLAY 0.659574 (-10790 1660);
PAINT MONO (-10790 1660);
DISPLAY INVISIBLE (-10790 1660);
FORCEPROP 1 LAST HDL_POWER GND
J 1
(-10775 1525);
DISPLAY 0.872340 (-10775 1525);
PAINT GREEN (-10775 1525);
DISPLAY INVISIBLE (-10775 1525);
FORCEPROP 2 LAST CDS_LIB logical_power
J 0
(-10800 1600);
PAINT MONO (-10800 1600);
DISPLAY INVISIBLE (-10800 1600);
FORCEPROP 1 LAST PATH I3
J 0
(-10725 1600);
DISPLAY 0.872340 (-10725 1600);
PAINT AQUA (-10725 1600);
DISPLAY INVISIBLE (-10725 1600);
FORCEADD UNIVERSAL_GND..1
(-9725 5275);
FORCEPROP 3 LASTPIN (-9725 5325) SIG_NAME GND\g
J 0
(-9715 5335);
DISPLAY 0.659574 (-9715 5335);
PAINT MONO (-9715 5335);
DISPLAY INVISIBLE (-9715 5335);
FORCEPROP 1 LAST HDL_POWER GND
J 1
(-9700 5200);
DISPLAY 0.872340 (-9700 5200);
PAINT GREEN (-9700 5200);
DISPLAY INVISIBLE (-9700 5200);
FORCEPROP 2 LAST CDS_LIB logical_power
J 0
(-9725 5275);
PAINT MONO (-9725 5275);
DISPLAY INVISIBLE (-9725 5275);
FORCEPROP 1 LAST PATH I30
J 0
(-9650 5275);
DISPLAY 0.872340 (-9650 5275);
PAINT AQUA (-9650 5275);
DISPLAY INVISIBLE (-9650 5275);
FORCEADD Q_CAP..1
(-9725 5525);
FORCEPROP 1 LAST PART_NUMBER CH5222KEB01
J 0
(-9675 5375);
DISPLAY 0.617021 (-9675 5375);
PAINT BLUE (-9675 5375);
DISPLAY INVISIBLE (-9675 5375);
FORCEPROP 1 LAST VOLTAGE 10V
J 0
(-9675 5525);
DISPLAY 0.617021 (-9675 5525);
PAINT SKYBLUE (-9675 5525);
FORCEPROP 1 LAST VALUE 2.2UF
J 0
(-9675 5575);
DISPLAY 0.617021 (-9675 5575);
PAINT SKYBLUE (-9675 5575);
FORCEPROP 1 LAST MATERIAL X6S
J 0
(-9675 5425);
DISPLAY 0.617021 (-9675 5425);
PAINT SKYBLUE (-9675 5425);
FORCEPROP 1 LAST TOLERANCE 10%
J 0
(-9675 5475);
DISPLAY 0.617021 (-9675 5475);
PAINT SKYBLUE (-9675 5475);
FORCEPROP 1 LAST PACK_TYPE C0402
J 0
(-9675 5325);
DISPLAY 0.617021 (-9675 5325);
PAINT SKYBLUE (-9675 5325);
FORCEPROP 1 LAST LOCATION PC1242_P1_1
J 0
(-9675 5625);
DISPLAY 0.617021 (-9675 5625);
PAINT AQUA (-9675 5625);
FORCEPROP 1 LASTPIN (-9725 5625) $PN 1
J 0
(-9715 5605);
DISPLAY 0.617021 (-9715 5605);
FORCEPROP 1 LASTPIN (-9725 5425) $PN 2
J 0
(-9715 5405);
DISPLAY 0.617021 (-9715 5405);
FORCEPROP 2 LAST CDS_LIB pure_quanta
J 0
(-9725 5525);
PAINT MONO (-9725 5525);
DISPLAY INVISIBLE (-9725 5525);
FORCEPROP 1 LAST PATH I31
J 0
(-9675 5675);
DISPLAY 0.978723 (-9675 5675);
PAINT WHITE (-9675 5675);
DISPLAY INVISIBLE (-9675 5675);
FORCEPROP 2 LAST $SEC 1
J 0
(-9675 5725);
DISPLAY 0.680851 (-9675 5725);
PAINT MONO (-9675 5725);
DISPLAY INVISIBLE (-9675 5725);
FORCEPROP 2 LAST CDS_SEC 1
J 0
(-9675 5725);
DISPLAY 1.021277 (-9675 5725);
DISPLAY INVISIBLE (-9675 5725);
FORCEADD Q_RES..2
(-10775 6175);
FORCEPROP 1 LAST PART_NUMBER CS00002JB13
J 0
(-10735 6050);
DISPLAY 0.617021 (-10735 6050);
PAINT BLUE (-10735 6050);
DISPLAY INVISIBLE (-10735 6050);
FORCEPROP 1 LAST WATTAGE 1/16W
J 0
(-10735 6150);
DISPLAY 0.617021 (-10735 6150);
PAINT SKYBLUE (-10735 6150);
FORCEPROP 1 LAST MATERIAL CHIP
J 0
(-10735 6100);
DISPLAY 0.617021 (-10735 6100);
PAINT SKYBLUE (-10735 6100);
FORCEPROP 1 LAST TOLERANCE 5%
J 0
(-10730 6200);
DISPLAY 0.617021 (-10730 6200);
PAINT SKYBLUE (-10730 6200);
FORCEPROP 1 LAST VALUE 0
J 0
(-10730 6250);
DISPLAY 0.617021 (-10730 6250);
PAINT SKYBLUE (-10730 6250);
FORCEPROP 1 LAST PACK_TYPE 0402LF
J 0
(-10735 6000);
DISPLAY 0.617021 (-10735 6000);
PAINT SKYBLUE (-10735 6000);
FORCEPROP 1 LAST LOCATION PR701
J 0
(-10730 6300);
DISPLAY 0.617021 (-10730 6300);
PAINT AQUA (-10730 6300);
FORCEPROP 2 LAST CDS_LIB pure_quanta
J 0
(-10775 6175);
DISPLAY INVISIBLE (-10775 6175);
FORCEPROP 1 LAST PATH I32
J 0
(-10725 6350);
DISPLAY 0.978723 (-10725 6350);
PAINT WHITE (-10725 6350);
DISPLAY INVISIBLE (-10725 6350);
FORCEPROP 0 LAST $SEC 1
J 0
(-10725 6350);
DISPLAY INVISIBLE (-10725 6350);
FORCEPROP 0 LAST CDS_SEC 1
J 0
(-10725 6350);
DISPLAY INVISIBLE (-10725 6350);
FORCEPROP 1 LASTPIN (-10775 6275) $PN 1
J 0
(-10770 6237);
DISPLAY 0.787234 (-10770 6237);
PAINT MONO (-10770 6237);
DISPLAY INVISIBLE (-10770 6237);
FORCEPROP 1 LASTPIN (-10775 6075) $PN 2
J 0
(-10770 6085);
DISPLAY 0.787234 (-10770 6085);
PAINT MONO (-10770 6085);
DISPLAY INVISIBLE (-10770 6085);
FORCEADD VCC15..1
(-10775 6400);
FORCEPROP 3 LASTPIN (-10775 6350) SIG_NAME P5V\g
J 0
(-10765 6360);
DISPLAY 0.659574 (-10765 6360);
PAINT MONO (-10765 6360);
DISPLAY INVISIBLE (-10765 6360);
FORCEPROP 1 LAST HDL_POWER P5V
J 1
(-10775 6450);
DISPLAY 0.617021 (-10775 6450);
PAINT GREEN (-10775 6450);
FORCEPROP 2 LAST CDS_LIB logical_power
J 0
(-10775 6400);
DISPLAY INVISIBLE (-10775 6400);
FORCEPROP 1 LAST PATH I33
J 0
(-10725 6425);
DISPLAY 0.872340 (-10725 6425);
PAINT AQUA (-10725 6425);
DISPLAY INVISIBLE (-10725 6425);
FORCEADD Q_RES..2
(-10125 6175);
FORCEPROP 1 LAST PART_NUMBER CS00002JB13
J 0
(-10085 6050);
DISPLAY 0.617021 (-10085 6050);
PAINT BLUE (-10085 6050);
DISPLAY INVISIBLE (-10085 6050);
FORCEPROP 1 LAST MATERIAL EMPTY
J 0
(-10085 6100);
DISPLAY 0.617021 (-10085 6100);
PAINT RED (-10085 6100);
FORCEPROP 1 LAST PACK_TYPE 0402LF
J 0
(-10085 6000);
DISPLAY 0.617021 (-10085 6000);
PAINT SKYBLUE (-10085 6000);
FORCEPROP 1 LAST TOLERANCE 5%
J 0
(-10080 6200);
DISPLAY 0.617021 (-10080 6200);
PAINT SKYBLUE (-10080 6200);
FORCEPROP 1 LAST WATTAGE 1/16W
J 0
(-10085 6150);
DISPLAY 0.617021 (-10085 6150);
PAINT SKYBLUE (-10085 6150);
FORCEPROP 1 LAST VALUE 0
J 0
(-10080 6250);
DISPLAY 0.617021 (-10080 6250);
PAINT SKYBLUE (-10080 6250);
FORCEPROP 1 LAST LOCATION PR703
J 0
(-10080 6300);
DISPLAY 0.617021 (-10080 6300);
PAINT AQUA (-10080 6300);
FORCEPROP 2 LAST CDS_LIB pure_quanta
J 0
(-10125 6175);
DISPLAY INVISIBLE (-10125 6175);
FORCEPROP 1 LAST PATH I34
J 0
(-10075 6350);
DISPLAY 0.978723 (-10075 6350);
PAINT WHITE (-10075 6350);
DISPLAY INVISIBLE (-10075 6350);
FORCEPROP 0 LAST $SEC 1
J 0
(-10075 6350);
DISPLAY INVISIBLE (-10075 6350);
FORCEPROP 0 LAST CDS_SEC 1
J 0
(-10075 6350);
DISPLAY INVISIBLE (-10075 6350);
FORCEPROP 1 LASTPIN (-10125 6275) $PN 1
J 0
(-10120 6237);
DISPLAY 0.787234 (-10120 6237);
PAINT MONO (-10120 6237);
DISPLAY INVISIBLE (-10120 6237);
FORCEPROP 1 LASTPIN (-10125 6075) $PN 2
J 0
(-10120 6085);
DISPLAY 0.787234 (-10120 6085);
PAINT MONO (-10120 6085);
DISPLAY INVISIBLE (-10120 6085);
FORCEADD VCC15..1
(-10125 6400);
FORCEPROP 3 LASTPIN (-10125 6350) SIG_NAME P3V3\g
J 0
(-10115 6360);
DISPLAY 0.659574 (-10115 6360);
PAINT MONO (-10115 6360);
DISPLAY INVISIBLE (-10115 6360);
FORCEPROP 1 LAST HDL_POWER P3V3
J 1
(-10125 6450);
DISPLAY 0.617021 (-10125 6450);
PAINT GREEN (-10125 6450);
FORCEPROP 2 LAST CDS_LIB logical_power
J 0
(-10125 6400);
DISPLAY INVISIBLE (-10125 6400);
FORCEPROP 1 LAST PATH I35
J 0
(-10075 6425);
DISPLAY 0.872340 (-10075 6425);
PAINT AQUA (-10075 6425);
DISPLAY INVISIBLE (-10075 6425);
FORCEADD UNIVERSAL_GND..1
(-8075 1150);
FORCEPROP 3 LASTPIN (-8075 1200) SIG_NAME GND\g
J 0
(-8065 1210);
DISPLAY 0.659574 (-8065 1210);
PAINT MONO (-8065 1210);
DISPLAY INVISIBLE (-8065 1210);
FORCEPROP 1 LAST HDL_POWER GND
J 1
(-8050 1075);
DISPLAY 0.872340 (-8050 1075);
PAINT GREEN (-8050 1075);
DISPLAY INVISIBLE (-8050 1075);
FORCEPROP 2 LAST CDS_LIB logical_power
J 0
(-8075 1150);
PAINT MONO (-8075 1150);
DISPLAY INVISIBLE (-8075 1150);
FORCEPROP 1 LAST PATH I36
J 0
(-8000 1150);
DISPLAY 0.872340 (-8000 1150);
PAINT AQUA (-8000 1150);
DISPLAY INVISIBLE (-8000 1150);
FORCEADD Q_CAP..1
(-7925 2775);
FORCEPROP 1 LAST PART_NUMBER TMP_QCH2336K1B12
J 0
(-7875 2625);
DISPLAY 0.617021 (-7875 2625);
PAINT BLUE (-7875 2625);
DISPLAY INVISIBLE (-7875 2625);
FORCEPROP 1 LAST VOLTAGE 50V
J 0
(-7875 2825);
DISPLAY 0.617021 (-7875 2825);
PAINT SKYBLUE (-7875 2825);
FORCEPROP 1 LAST PACK_TYPE 0402
J 0
(-7875 2675);
DISPLAY 0.617021 (-7875 2675);
PAINT SKYBLUE (-7875 2675);
FORCEPROP 1 LAST MATERIAL X7R
J 0
(-7875 2725);
DISPLAY 0.617021 (-7875 2725);
PAINT SKYBLUE (-7875 2725);
FORCEPROP 1 LAST VALUE 3300PF
J 0
(-7875 2875);
DISPLAY 0.617021 (-7875 2875);
PAINT SKYBLUE (-7875 2875);
FORCEPROP 1 LAST TOLERANCE 10%
J 0
(-7875 2775);
DISPLAY 0.617021 (-7875 2775);
PAINT SKYBLUE (-7875 2775);
FORCEPROP 1 LAST LOCATION PC398_P1_2
J 0
(-7875 2925);
DISPLAY 0.617021 (-7875 2925);
PAINT AQUA (-7875 2925);
FORCEPROP 1 LASTPIN (-7925 2875) $PN 1
J 0
(-7915 2855);
DISPLAY 0.617021 (-7915 2855);
PAINT MONO (-7915 2855);
FORCEPROP 1 LASTPIN (-7925 2675) $PN 2
J 0
(-7915 2655);
DISPLAY 0.617021 (-7915 2655);
PAINT MONO (-7915 2655);
FORCEPROP 2 LAST CDS_LIB pure_quanta
J 0
(-7925 2775);
DISPLAY INVISIBLE (-7925 2775);
FORCEPROP 1 LAST PATH I37
J 0
(-7875 2925);
DISPLAY 0.978723 (-7875 2925);
PAINT WHITE (-7875 2925);
DISPLAY INVISIBLE (-7875 2925);
FORCEPROP 1 LAST LOCATION PC398_P1_2
J 0
(-7875 2975);
DISPLAY 1.021277 (-7875 2975);
PAINT AQUA (-7875 2975);
DISPLAY INVISIBLE (-7875 2975);
FORCEPROP 0 LAST $SEC 1
J 0
(-7875 2975);
DISPLAY 0.680851 (-7875 2975);
PAINT MONO (-7875 2975);
DISPLAY INVISIBLE (-7875 2975);
FORCEPROP 0 LAST CDS_SEC 1
J 0
(-7875 2975);
DISPLAY 1.021277 (-7875 2975);
DISPLAY INVISIBLE (-7875 2975);
FORCEADD Q_RES..1
(-7225 2325);
FORCEPROP 1 LAST PART_NUMBER CS-3302FB01
J 0
(-7325 2375);
DISPLAY 0.617021 (-7325 2375);
PAINT BLUE (-7325 2375);
DISPLAY INVISIBLE (-7325 2375);
FORCEPROP 1 LAST VALUE 3.3
J 2
(-7100 2325);
DISPLAY 0.617021 (-7100 2325);
PAINT SKYBLUE (-7100 2325);
FORCEPROP 1 LAST WATTAGE 1/16W
J 2
(-6975 2400);
DISPLAY 0.617021 (-6975 2400);
PAINT SKYBLUE (-6975 2400);
FORCEPROP 1 LAST MATERIAL CHIP
J 0
(-7325 2425);
DISPLAY 0.617021 (-7325 2425);
PAINT SKYBLUE (-7325 2425);
FORCEPROP 1 LAST TOLERANCE 1%
J 0
(-7075 2325);
DISPLAY 0.617021 (-7075 2325);
PAINT SKYBLUE (-7075 2325);
FORCEPROP 1 LAST PACK_TYPE 0402LF
J 0
(-7325 2400);
DISPLAY 0.617021 (-7325 2400);
PAINT SKYBLUE (-7325 2400);
FORCEPROP 1 LAST LOCATION PR1801
J 0
(-7475 2325);
DISPLAY 0.617021 (-7475 2325);
PAINT AQUA (-7475 2325);
FORCEPROP 1 LASTPIN (-7325 2325) $PN 1
J 0
(-7313 2337);
DISPLAY 0.617021 (-7313 2337);
FORCEPROP 1 LASTPIN (-7125 2325) $PN 2
J 0
(-7163 2337);
DISPLAY 0.617021 (-7163 2337);
FORCEPROP 2 LAST CDS_LIB pure_quanta
J 0
(-7225 2325);
PAINT MONO (-7225 2325);
DISPLAY INVISIBLE (-7225 2325);
FORCEPROP 1 LAST PATH I38
J 0
(-7275 2475);
DISPLAY 0.978723 (-7275 2475);
PAINT WHITE (-7275 2475);
DISPLAY INVISIBLE (-7275 2475);
FORCEPROP 2 LAST $SEC 1
J 0
(-7275 2525);
DISPLAY 0.680851 (-7275 2525);
PAINT MONO (-7275 2525);
DISPLAY INVISIBLE (-7275 2525);
FORCEPROP 2 LAST CDS_SEC 1
J 0
(-7275 2525);
DISPLAY 1.021277 (-7275 2525);
DISPLAY INVISIBLE (-7275 2525);
FORCEADD Q_CAP..1
(-7525 2775);
FORCEPROP 1 LAST PART_NUMBER CH5103KEB01
J 0
(-7475 2625);
DISPLAY 0.617021 (-7475 2625);
PAINT BLUE (-7475 2625);
DISPLAY INVISIBLE (-7475 2625);
FORCEPROP 1 LAST TOLERANCE 10%
J 0
(-7475 2775);
DISPLAY 0.617021 (-7475 2775);
PAINT SKYBLUE (-7475 2775);
FORCEPROP 1 LAST VALUE 1UF
J 0
(-7475 2875);
DISPLAY 0.617021 (-7475 2875);
PAINT SKYBLUE (-7475 2875);
FORCEPROP 1 LAST VOLTAGE 16V
J 0
(-7475 2825);
DISPLAY 0.617021 (-7475 2825);
PAINT SKYBLUE (-7475 2825);
FORCEPROP 1 LAST PACK_TYPE C0402
J 0
(-7475 2675);
DISPLAY 0.617021 (-7475 2675);
PAINT SKYBLUE (-7475 2675);
FORCEPROP 1 LAST MATERIAL X6S
J 0
(-7475 2725);
DISPLAY 0.617021 (-7475 2725);
PAINT SKYBLUE (-7475 2725);
FORCEPROP 1 LAST LOCATION PC400_P1_2
J 0
(-7475 2925);
DISPLAY 0.617021 (-7475 2925);
PAINT AQUA (-7475 2925);
FORCEPROP 1 LASTPIN (-7525 2875) $PN 1
J 0
(-7515 2855);
DISPLAY 0.617021 (-7515 2855);
PAINT MONO (-7515 2855);
FORCEPROP 1 LASTPIN (-7525 2675) $PN 2
J 0
(-7515 2655);
DISPLAY 0.617021 (-7515 2655);
PAINT MONO (-7515 2655);
FORCEPROP 2 LAST CDS_LIB pure_quanta
J 0
(-7525 2775);
DISPLAY INVISIBLE (-7525 2775);
FORCEPROP 1 LAST PATH I39
J 0
(-7475 2925);
DISPLAY 0.978723 (-7475 2925);
PAINT WHITE (-7475 2925);
DISPLAY INVISIBLE (-7475 2925);
FORCEPROP 1 LAST LOCATION PC400_P1_2
J 0
(-7475 2975);
DISPLAY 1.021277 (-7475 2975);
PAINT AQUA (-7475 2975);
DISPLAY INVISIBLE (-7475 2975);
FORCEPROP 0 LAST $SEC 1
J 0
(-7475 2975);
DISPLAY 0.680851 (-7475 2975);
PAINT MONO (-7475 2975);
DISPLAY INVISIBLE (-7475 2975);
FORCEPROP 0 LAST CDS_SEC 1
J 0
(-7475 2975);
DISPLAY 1.021277 (-7475 2975);
DISPLAY INVISIBLE (-7475 2975);
FORCEADD OFFPAGE..1
(-10275 1275);
FORCEPROP 2 LAST $XR0 284 
J 0
(-10557 1275);
DISPLAY 0.638298 (-10557 1275);
PAINT MONO (-10557 1275);
FORCEPROP 1 LAST COMMENT_BODY TRUE
J 0
(-10150 1175);
DISPLAY 0.872340 (-10150 1175);
PAINT GREEN (-10150 1175);
DISPLAY INVISIBLE (-10150 1175);
FORCEPROP 1 LAST OFFPAGE TRUE
J 0
(-9950 1150);
DISPLAY 0.872340 (-9950 1150);
PAINT GREEN (-9950 1150);
DISPLAY INVISIBLE (-9950 1150);
FORCEPROP 2 LAST CDS_LIB standard
J 0
(-10275 1275);
DISPLAY INVISIBLE (-10275 1275);
FORCEPROP 2 LAST PATH I4
J 0
(-10550 1325);
DISPLAY 1.021277 (-10550 1325);
DISPLAY INVISIBLE (-10550 1325);
FORCEADD Q_CAP..1
(-7125 2775);
FORCEPROP 1 LAST PART_NUMBER CH6223MEA01
J 0
(-7075 2625);
DISPLAY 0.617021 (-7075 2625);
PAINT BLUE (-7075 2625);
DISPLAY INVISIBLE (-7075 2625);
FORCEPROP 1 LAST TOLERANCE 20%
J 0
(-7075 2775);
DISPLAY 0.617021 (-7075 2775);
PAINT SKYBLUE (-7075 2775);
FORCEPROP 1 LAST PACK_TYPE C0805
J 0
(-7075 2675);
DISPLAY 0.617021 (-7075 2675);
PAINT SKYBLUE (-7075 2675);
FORCEPROP 1 LAST MATERIAL X6S
J 0
(-7075 2725);
DISPLAY 0.617021 (-7075 2725);
PAINT SKYBLUE (-7075 2725);
FORCEPROP 1 LAST VALUE 22UF
J 0
(-7075 2875);
DISPLAY 0.617021 (-7075 2875);
PAINT SKYBLUE (-7075 2875);
FORCEPROP 1 LAST VOLTAGE 16V
J 0
(-7075 2825);
DISPLAY 0.617021 (-7075 2825);
PAINT SKYBLUE (-7075 2825);
FORCEPROP 1 LAST LOCATION PC404_P1_2
J 0
(-7075 2925);
DISPLAY 0.617021 (-7075 2925);
PAINT AQUA (-7075 2925);
FORCEPROP 1 LASTPIN (-7125 2875) $PN 1
J 0
(-7115 2855);
DISPLAY 0.617021 (-7115 2855);
PAINT MONO (-7115 2855);
FORCEPROP 1 LASTPIN (-7125 2675) $PN 2
J 0
(-7115 2655);
DISPLAY 0.617021 (-7115 2655);
PAINT MONO (-7115 2655);
FORCEPROP 2 LAST CDS_LIB pure_quanta
J 0
(-7125 2775);
DISPLAY INVISIBLE (-7125 2775);
FORCEPROP 1 LAST PATH I40
J 0
(-7075 2925);
DISPLAY 0.978723 (-7075 2925);
PAINT WHITE (-7075 2925);
DISPLAY INVISIBLE (-7075 2925);
FORCEPROP 1 LAST LOCATION PC404_P1_2
J 0
(-7075 2975);
DISPLAY 1.021277 (-7075 2975);
PAINT AQUA (-7075 2975);
DISPLAY INVISIBLE (-7075 2975);
FORCEPROP 0 LAST $SEC 1
J 0
(-7075 2975);
DISPLAY 0.680851 (-7075 2975);
PAINT MONO (-7075 2975);
DISPLAY INVISIBLE (-7075 2975);
FORCEPROP 0 LAST CDS_SEC 1
J 0
(-7075 2975);
DISPLAY 1.021277 (-7075 2975);
DISPLAY INVISIBLE (-7075 2975);
FORCEADD Q_RES..1
(-6025 1625);
FORCEPROP 1 LAST PART_NUMBER CS00002JB13
J 0
(-6125 1575);
DISPLAY 0.617021 (-6125 1575);
PAINT BLUE (-6125 1575);
DISPLAY INVISIBLE (-6125 1575);
FORCEPROP 1 LAST WATTAGE 1/16W
J 2
(-5650 1525);
DISPLAY 0.617021 (-5650 1525);
PAINT SKYBLUE (-5650 1525);
FORCEPROP 1 LAST MATERIAL CHIP
J 0
(-6125 1525);
DISPLAY 0.617021 (-6125 1525);
PAINT SKYBLUE (-6125 1525);
FORCEPROP 1 LAST TOLERANCE 5%
J 0
(-5850 1625);
DISPLAY 0.617021 (-5850 1625);
PAINT SKYBLUE (-5850 1625);
FORCEPROP 1 LAST PACK_TYPE 0402LF
J 0
(-6025 1525);
DISPLAY 0.617021 (-6025 1525);
PAINT SKYBLUE (-6025 1525);
FORCEPROP 1 LAST VALUE 0
J 2
(-5875 1625);
DISPLAY 0.617021 (-5875 1625);
PAINT SKYBLUE (-5875 1625);
FORCEPROP 1 LAST LOCATION PR1332
J 0
(-6275 1625);
DISPLAY 0.617021 (-6275 1625);
PAINT AQUA (-6275 1625);
FORCEPROP 1 LASTPIN (-6125 1625) $PN 1
J 0
(-6113 1637);
DISPLAY 0.617021 (-6113 1637);
FORCEPROP 1 LASTPIN (-5925 1625) $PN 2
J 0
(-5963 1637);
DISPLAY 0.617021 (-5963 1637);
FORCEPROP 2 LAST CDS_LIB pure_quanta
J 0
(-6025 1625);
PAINT MONO (-6025 1625);
DISPLAY INVISIBLE (-6025 1625);
FORCEPROP 1 LAST PATH I41
J 0
(-6075 1775);
DISPLAY 0.978723 (-6075 1775);
PAINT WHITE (-6075 1775);
DISPLAY INVISIBLE (-6075 1775);
FORCEPROP 2 LAST $SEC 1
J 0
(-6075 1825);
DISPLAY 0.680851 (-6075 1825);
PAINT MONO (-6075 1825);
DISPLAY INVISIBLE (-6075 1825);
FORCEPROP 2 LAST CDS_SEC 1
J 0
(-6075 1825);
DISPLAY 1.021277 (-6075 1825);
DISPLAY INVISIBLE (-6075 1825);
FORCEADD Q_CAP..1
(-6725 2775);
FORCEPROP 1 LAST PART_NUMBER CH6223MEA01
J 0
(-6675 2625);
DISPLAY 0.617021 (-6675 2625);
PAINT BLUE (-6675 2625);
DISPLAY INVISIBLE (-6675 2625);
FORCEPROP 1 LAST TOLERANCE 20%
J 0
(-6675 2775);
DISPLAY 0.617021 (-6675 2775);
PAINT SKYBLUE (-6675 2775);
FORCEPROP 1 LAST MATERIAL X6S
J 0
(-6675 2725);
DISPLAY 0.617021 (-6675 2725);
PAINT SKYBLUE (-6675 2725);
FORCEPROP 1 LAST VOLTAGE 16V
J 0
(-6675 2825);
DISPLAY 0.617021 (-6675 2825);
PAINT SKYBLUE (-6675 2825);
FORCEPROP 1 LAST VALUE 22UF
J 0
(-6675 2875);
DISPLAY 0.617021 (-6675 2875);
PAINT SKYBLUE (-6675 2875);
FORCEPROP 1 LAST PACK_TYPE C0805
J 0
(-6675 2675);
DISPLAY 0.617021 (-6675 2675);
PAINT SKYBLUE (-6675 2675);
FORCEPROP 1 LAST LOCATION PC406_P1_2
J 0
(-6675 2925);
DISPLAY 0.617021 (-6675 2925);
PAINT AQUA (-6675 2925);
FORCEPROP 1 LASTPIN (-6725 2875) $PN 1
J 0
(-6715 2855);
DISPLAY 0.617021 (-6715 2855);
PAINT MONO (-6715 2855);
FORCEPROP 1 LASTPIN (-6725 2675) $PN 2
J 0
(-6715 2655);
DISPLAY 0.617021 (-6715 2655);
PAINT MONO (-6715 2655);
FORCEPROP 2 LAST CDS_LIB pure_quanta
J 0
(-6725 2775);
DISPLAY INVISIBLE (-6725 2775);
FORCEPROP 1 LAST PATH I42
J 0
(-6675 2925);
DISPLAY 0.978723 (-6675 2925);
PAINT WHITE (-6675 2925);
DISPLAY INVISIBLE (-6675 2925);
FORCEPROP 1 LAST LOCATION PC406_P1_2
J 0
(-6675 2975);
DISPLAY 1.021277 (-6675 2975);
PAINT AQUA (-6675 2975);
DISPLAY INVISIBLE (-6675 2975);
FORCEPROP 0 LAST $SEC 1
J 0
(-6675 2975);
DISPLAY 0.680851 (-6675 2975);
PAINT MONO (-6675 2975);
DISPLAY INVISIBLE (-6675 2975);
FORCEPROP 0 LAST CDS_SEC 1
J 0
(-6675 2975);
DISPLAY 1.021277 (-6675 2975);
DISPLAY INVISIBLE (-6675 2975);
FORCEADD Q_CAP..1
R 2
(-6300 2150);
FORCEPROP 1 LAST PART_NUMBER CH4106K1B01
J 2
(-6350 2100);
DISPLAY 0.617021 (-6350 2100);
PAINT BLUE (-6350 2100);
DISPLAY INVISIBLE (-6350 2100);
FORCEPROP 1 LAST VALUE 100NF
J 2
(-6350 2200);
DISPLAY 0.617021 (-6350 2200);
PAINT SKYBLUE (-6350 2200);
FORCEPROP 1 LAST MATERIAL X7R
J 2
(-6350 2125);
DISPLAY 0.617021 (-6350 2125);
PAINT SKYBLUE (-6350 2125);
FORCEPROP 1 LAST TOLERANCE 10%
J 2
(-6350 2150);
DISPLAY 0.617021 (-6350 2150);
PAINT SKYBLUE (-6350 2150);
FORCEPROP 1 LAST VOLTAGE 50V
J 2
(-6350 2175);
DISPLAY 0.617021 (-6350 2175);
PAINT SKYBLUE (-6350 2175);
FORCEPROP 1 LAST PACK_TYPE C0402
J 2
(-6350 2075);
DISPLAY 0.617021 (-6350 2075);
PAINT SKYBLUE (-6350 2075);
FORCEPROP 1 LAST LOCATION PC402
J 2
(-6350 2225);
DISPLAY 0.617021 (-6350 2225);
PAINT AQUA (-6350 2225);
FORCEPROP 1 LASTPIN (-6300 2250) $PN 1
J 2
(-6310 2230);
DISPLAY 0.617021 (-6310 2230);
FORCEPROP 1 LASTPIN (-6300 2050) $PN 2
J 2
(-6310 2030);
DISPLAY 0.617021 (-6310 2030);
FORCEPROP 2 LAST CDS_LIB pure_quanta
J 2
(-6300 2150);
PAINT MONO (-6300 2150);
DISPLAY INVISIBLE (-6300 2150);
FORCEPROP 1 LAST PATH I43
J 2
(-6350 2300);
DISPLAY 0.978723 (-6350 2300);
PAINT WHITE (-6350 2300);
DISPLAY INVISIBLE (-6350 2300);
FORCEPROP 2 LAST $SEC 1
J 0
(-6350 2350);
DISPLAY 0.680851 (-6350 2350);
PAINT MONO (-6350 2350);
DISPLAY INVISIBLE (-6350 2350);
FORCEPROP 2 LAST CDS_SEC 1
J 0
(-6350 2350);
DISPLAY 1.021277 (-6350 2350);
DISPLAY INVISIBLE (-6350 2350);
FORCEADD Q_INDUCTOR..1
(-6025 1900);
FORCEPROP 1 LAST PART_NUMBER CV+13^0KZ11
J 0
(-6150 2010);
DISPLAY 0.617021 (-6150 2010);
PAINT BLUE (-6150 2010);
DISPLAY INVISIBLE (-6150 2010);
FORCEPROP 1 LAST MATERIAL IND
J 0
(-6150 1955);
DISPLAY 0.617021 (-6150 1955);
PAINT SKYBLUE (-6150 1955);
FORCEPROP 2 LAST PACK_TYPE SMLF
J 0
(-6150 2100);
DISPLAY 0.617021 (-6150 2100);
PAINT SKYBLUE (-6150 2100);
FORCEPROP 2 LAST VALUE 130NH/106A
J 0
(-6150 2150);
DISPLAY 0.617021 (-6150 2150);
PAINT SKYBLUE (-6150 2150);
FORCEPROP 1 LAST LOCATION PL19
J 0
(-6150 2060);
DISPLAY 0.617021 (-6150 2060);
PAINT AQUA (-6150 2060);
FORCEPROP 0 LASTPIN (-6125 1875) $PN 1
J 2
(-6135 1885);
DISPLAY 0.617021 (-6135 1885);
PAINT MONO (-6135 1885);
FORCEPROP 0 LASTPIN (-5925 1875) $PN 2
J 0
(-5915 1885);
DISPLAY 0.617021 (-5915 1885);
PAINT MONO (-5915 1885);
FORCEPROP 2 LAST CDS_LIB pure_quanta
J 0
(-6025 1900);
DISPLAY INVISIBLE (-6025 1900);
FORCEPROP 1 LAST NEEDS_NO_SIZE TRUE
J 0
(-6025 1900);
DISPLAY 0.468085 (-6025 1900);
PAINT GREEN (-6025 1900);
DISPLAY INVISIBLE (-6025 1900);
FORCEPROP 1 LAST PATH I44
J 0
(-5950 1955);
DISPLAY 0.723404 (-5950 1955);
PAINT GREEN (-5950 1955);
DISPLAY INVISIBLE (-5950 1955);
FORCEPROP 0 LAST $SEC 1
J 0
(-6150 2200);
DISPLAY 0.680851 (-6150 2200);
PAINT MONO (-6150 2200);
DISPLAY INVISIBLE (-6150 2200);
FORCEPROP 0 LAST CDS_SEC 1
J 0
(-6150 2200);
DISPLAY 1.021277 (-6150 2200);
DISPLAY INVISIBLE (-6150 2200);
FORCEADD UNIVERSAL_GND..1
(-6125 2400);
FORCEPROP 3 LASTPIN (-6125 2450) SIG_NAME GND\g
J 0
(-6115 2460);
DISPLAY 0.659574 (-6115 2460);
PAINT MONO (-6115 2460);
DISPLAY INVISIBLE (-6115 2460);
FORCEPROP 1 LAST HDL_POWER GND
J 1
(-6100 2325);
DISPLAY 0.872340 (-6100 2325);
PAINT GREEN (-6100 2325);
DISPLAY INVISIBLE (-6100 2325);
FORCEPROP 2 LAST CDS_LIB logical_power
J 0
(-6125 2400);
PAINT MONO (-6125 2400);
DISPLAY INVISIBLE (-6125 2400);
FORCEPROP 1 LAST PATH I45
J 0
(-6050 2400);
DISPLAY 0.872340 (-6050 2400);
PAINT AQUA (-6050 2400);
DISPLAY INVISIBLE (-6050 2400);
FORCEADD Q_CAP..1
(-6275 2775);
FORCEPROP 1 LAST PART_NUMBER CH6223MEA01
J 0
(-6225 2625);
DISPLAY 0.617021 (-6225 2625);
PAINT BLUE (-6225 2625);
DISPLAY INVISIBLE (-6225 2625);
FORCEPROP 1 LAST TOLERANCE 20%
J 0
(-6225 2775);
DISPLAY 0.617021 (-6225 2775);
PAINT SKYBLUE (-6225 2775);
FORCEPROP 1 LAST PACK_TYPE C0805
J 0
(-6225 2675);
DISPLAY 0.617021 (-6225 2675);
PAINT SKYBLUE (-6225 2675);
FORCEPROP 1 LAST VOLTAGE 16V
J 0
(-6225 2825);
DISPLAY 0.617021 (-6225 2825);
PAINT SKYBLUE (-6225 2825);
FORCEPROP 1 LAST MATERIAL X6S
J 0
(-6225 2725);
DISPLAY 0.617021 (-6225 2725);
PAINT SKYBLUE (-6225 2725);
FORCEPROP 1 LAST VALUE 22UF
J 0
(-6225 2875);
DISPLAY 0.617021 (-6225 2875);
PAINT SKYBLUE (-6225 2875);
FORCEPROP 1 LAST LOCATION PC725_P1_2
J 0
(-6225 2925);
DISPLAY 0.617021 (-6225 2925);
PAINT AQUA (-6225 2925);
FORCEPROP 1 LASTPIN (-6275 2875) $PN 1
J 0
(-6265 2855);
DISPLAY 0.787234 (-6265 2855);
PAINT MONO (-6265 2855);
FORCEPROP 1 LASTPIN (-6275 2675) $PN 2
J 0
(-6265 2655);
DISPLAY 0.787234 (-6265 2655);
PAINT MONO (-6265 2655);
FORCEPROP 2 LAST CDS_LIB pure_quanta
J 0
(-6275 2775);
DISPLAY INVISIBLE (-6275 2775);
FORCEPROP 1 LAST PATH I46
J 0
(-6225 2925);
DISPLAY 0.978723 (-6225 2925);
PAINT WHITE (-6225 2925);
DISPLAY INVISIBLE (-6225 2925);
FORCEPROP 0 LAST $SEC 1
J 0
(-6225 2925);
DISPLAY 0.680851 (-6225 2925);
PAINT MONO (-6225 2925);
DISPLAY INVISIBLE (-6225 2925);
FORCEPROP 0 LAST CDS_SEC 1
J 0
(-6225 2925);
DISPLAY 1.021277 (-6225 2925);
DISPLAY INVISIBLE (-6225 2925);
FORCEADD VCC15..1
(-6125 3150);
FORCEPROP 3 LASTPIN (-6125 3100) SIG_NAME SW_P12V_PVCCFA_EHV_FIVRA_CPU1_L\g
J 0
(-6115 3110);
DISPLAY 0.659574 (-6115 3110);
PAINT MONO (-6115 3110);
DISPLAY INVISIBLE (-6115 3110);
FORCEPROP 1 LAST HDL_POWER SW_P12V_PVCCFA_EHV_FIVRA_CPU1_L
J 1
(-6075 3200);
DISPLAY 0.617021 (-6075 3200);
PAINT GREEN (-6075 3200);
FORCEPROP 2 LAST CDS_LIB logical_power
J 0
(-6125 3150);
DISPLAY INVISIBLE (-6125 3150);
FORCEPROP 1 LAST PATH I47
J 0
(-6075 3175);
DISPLAY 0.872340 (-6075 3175);
PAINT AQUA (-6075 3175);
DISPLAY INVISIBLE (-6075 3175);
FORCEADD UNIVERSAL_GND..1
(-8075 3950);
FORCEPROP 3 LASTPIN (-8075 4000) SIG_NAME GND\g
J 0
(-8065 4010);
DISPLAY 0.659574 (-8065 4010);
PAINT MONO (-8065 4010);
DISPLAY INVISIBLE (-8065 4010);
FORCEPROP 1 LAST HDL_POWER GND
J 1
(-8050 3875);
DISPLAY 0.872340 (-8050 3875);
PAINT GREEN (-8050 3875);
DISPLAY INVISIBLE (-8050 3875);
FORCEPROP 2 LAST CDS_LIB logical_power
J 0
(-8075 3950);
PAINT MONO (-8075 3950);
DISPLAY INVISIBLE (-8075 3950);
FORCEPROP 1 LAST PATH I48
J 0
(-8000 3950);
DISPLAY 0.872340 (-8000 3950);
PAINT AQUA (-8000 3950);
DISPLAY INVISIBLE (-8000 3950);
FORCEADD Q_CAP..1
(-7925 5575);
FORCEPROP 1 LAST PART_NUMBER TMP_QCH2336K1B12
J 0
(-7875 5425);
DISPLAY 0.617021 (-7875 5425);
PAINT BLUE (-7875 5425);
DISPLAY INVISIBLE (-7875 5425);
FORCEPROP 1 LAST MATERIAL X7R
J 0
(-7875 5525);
DISPLAY 0.617021 (-7875 5525);
PAINT SKYBLUE (-7875 5525);
FORCEPROP 1 LAST TOLERANCE 10%
J 0
(-7875 5575);
DISPLAY 0.617021 (-7875 5575);
PAINT SKYBLUE (-7875 5575);
FORCEPROP 1 LAST VALUE 3300PF
J 0
(-7875 5675);
DISPLAY 0.617021 (-7875 5675);
PAINT SKYBLUE (-7875 5675);
FORCEPROP 1 LAST VOLTAGE 50V
J 0
(-7875 5625);
DISPLAY 0.617021 (-7875 5625);
PAINT SKYBLUE (-7875 5625);
FORCEPROP 1 LAST PACK_TYPE 0402
J 0
(-7875 5475);
DISPLAY 0.617021 (-7875 5475);
PAINT SKYBLUE (-7875 5475);
FORCEPROP 1 LAST LOCATION PC397_P1_1
J 0
(-7875 5725);
DISPLAY 0.617021 (-7875 5725);
PAINT AQUA (-7875 5725);
FORCEPROP 1 LASTPIN (-7925 5675) $PN 1
J 0
(-7915 5655);
DISPLAY 0.617021 (-7915 5655);
PAINT MONO (-7915 5655);
FORCEPROP 1 LASTPIN (-7925 5475) $PN 2
J 0
(-7915 5455);
DISPLAY 0.617021 (-7915 5455);
PAINT MONO (-7915 5455);
FORCEPROP 2 LAST CDS_LIB pure_quanta
J 0
(-7925 5575);
DISPLAY INVISIBLE (-7925 5575);
FORCEPROP 1 LAST PATH I49
J 0
(-7875 5725);
DISPLAY 0.978723 (-7875 5725);
PAINT WHITE (-7875 5725);
DISPLAY INVISIBLE (-7875 5725);
FORCEPROP 1 LAST LOCATION PC397_P1_1
J 0
(-7875 5775);
DISPLAY 1.021277 (-7875 5775);
PAINT AQUA (-7875 5775);
DISPLAY INVISIBLE (-7875 5775);
FORCEPROP 0 LAST $SEC 1
J 0
(-7875 5775);
DISPLAY 0.680851 (-7875 5775);
PAINT MONO (-7875 5775);
DISPLAY INVISIBLE (-7875 5775);
FORCEPROP 0 LAST CDS_SEC 1
J 0
(-7875 5775);
DISPLAY 1.021277 (-7875 5775);
DISPLAY INVISIBLE (-7875 5775);
FORCEADD OFFPAGE..1
(-10275 1775);
FORCEPROP 2 LAST $XR6 290 
J 0
(-11277 1775);
DISPLAY 0.638298 (-11277 1775);
PAINT MONO (-11277 1775);
FORCEPROP 2 LAST $XR5 289 
J 0
(-11157 1775);
DISPLAY 0.638298 (-11157 1775);
PAINT MONO (-11157 1775);
FORCEPROP 2 LAST $XR4 288 
J 0
(-11037 1775);
DISPLAY 0.638298 (-11037 1775);
PAINT MONO (-11037 1775);
FORCEPROP 2 LAST $XR3 287 
J 0
(-10917 1775);
DISPLAY 0.638298 (-10917 1775);
PAINT MONO (-10917 1775);
FORCEPROP 2 LAST $XR2 286 
J 0
(-10797 1775);
DISPLAY 0.638298 (-10797 1775);
PAINT MONO (-10797 1775);
FORCEPROP 2 LAST $XR1 285 
J 0
(-10677 1775);
DISPLAY 0.638298 (-10677 1775);
PAINT MONO (-10677 1775);
FORCEPROP 2 LAST $XR0 284 
J 0
(-10557 1775);
DISPLAY 0.638298 (-10557 1775);
PAINT MONO (-10557 1775);
FORCEPROP 1 LAST COMMENT_BODY TRUE
J 0
(-10150 1675);
DISPLAY 0.872340 (-10150 1675);
PAINT GREEN (-10150 1675);
DISPLAY INVISIBLE (-10150 1675);
FORCEPROP 1 LAST OFFPAGE TRUE
J 0
(-9950 1650);
DISPLAY 0.872340 (-9950 1650);
PAINT GREEN (-9950 1650);
DISPLAY INVISIBLE (-9950 1650);
FORCEPROP 2 LAST CDS_LIB standard
J 0
(-10275 1775);
DISPLAY INVISIBLE (-10275 1775);
FORCEPROP 2 LAST PATH I5
J 0
(-10550 1825);
DISPLAY 1.021277 (-10550 1825);
DISPLAY INVISIBLE (-10550 1825);
FORCEADD Q_RES..1
(-7225 5125);
FORCEPROP 1 LAST PART_NUMBER CS-3302FB01
J 0
(-7325 5175);
DISPLAY 0.617021 (-7325 5175);
PAINT BLUE (-7325 5175);
DISPLAY INVISIBLE (-7325 5175);
FORCEPROP 1 LAST TOLERANCE 1%
J 0
(-7075 5125);
DISPLAY 0.617021 (-7075 5125);
PAINT SKYBLUE (-7075 5125);
FORCEPROP 1 LAST PACK_TYPE 0402LF
J 0
(-7325 5200);
DISPLAY 0.617021 (-7325 5200);
PAINT SKYBLUE (-7325 5200);
FORCEPROP 1 LAST WATTAGE 1/16W
J 2
(-6975 5200);
DISPLAY 0.617021 (-6975 5200);
PAINT SKYBLUE (-6975 5200);
FORCEPROP 1 LAST VALUE 3.3
J 2
(-7100 5125);
DISPLAY 0.617021 (-7100 5125);
PAINT SKYBLUE (-7100 5125);
FORCEPROP 1 LAST MATERIAL CHIP
J 0
(-7325 5225);
DISPLAY 0.617021 (-7325 5225);
PAINT SKYBLUE (-7325 5225);
FORCEPROP 1 LAST LOCATION PR1800
J 0
(-7475 5125);
DISPLAY 0.617021 (-7475 5125);
PAINT AQUA (-7475 5125);
FORCEPROP 1 LASTPIN (-7325 5125) $PN 1
J 0
(-7313 5137);
DISPLAY 0.617021 (-7313 5137);
FORCEPROP 1 LASTPIN (-7125 5125) $PN 2
J 0
(-7163 5137);
DISPLAY 0.617021 (-7163 5137);
FORCEPROP 2 LAST CDS_LIB pure_quanta
J 0
(-7225 5125);
PAINT MONO (-7225 5125);
DISPLAY INVISIBLE (-7225 5125);
FORCEPROP 1 LAST PATH I50
J 0
(-7275 5275);
DISPLAY 0.978723 (-7275 5275);
PAINT WHITE (-7275 5275);
DISPLAY INVISIBLE (-7275 5275);
FORCEPROP 2 LAST $SEC 1
J 0
(-7275 5325);
DISPLAY 0.680851 (-7275 5325);
PAINT MONO (-7275 5325);
DISPLAY INVISIBLE (-7275 5325);
FORCEPROP 2 LAST CDS_SEC 1
J 0
(-7275 5325);
DISPLAY 1.021277 (-7275 5325);
DISPLAY INVISIBLE (-7275 5325);
FORCEADD Q_CAP..1
(-7525 5575);
FORCEPROP 1 LAST PART_NUMBER CH5103KEB01
J 0
(-7475 5425);
DISPLAY 0.617021 (-7475 5425);
PAINT BLUE (-7475 5425);
DISPLAY INVISIBLE (-7475 5425);
FORCEPROP 1 LAST MATERIAL X6S
J 0
(-7475 5525);
DISPLAY 0.617021 (-7475 5525);
PAINT SKYBLUE (-7475 5525);
FORCEPROP 1 LAST VALUE 1UF
J 0
(-7475 5675);
DISPLAY 0.617021 (-7475 5675);
PAINT SKYBLUE (-7475 5675);
FORCEPROP 1 LAST VOLTAGE 16V
J 0
(-7475 5625);
DISPLAY 0.617021 (-7475 5625);
PAINT SKYBLUE (-7475 5625);
FORCEPROP 1 LAST PACK_TYPE C0402
J 0
(-7475 5475);
DISPLAY 0.617021 (-7475 5475);
PAINT SKYBLUE (-7475 5475);
FORCEPROP 1 LAST TOLERANCE 10%
J 0
(-7475 5575);
DISPLAY 0.617021 (-7475 5575);
PAINT SKYBLUE (-7475 5575);
FORCEPROP 1 LAST LOCATION PC399_P1_1
J 0
(-7475 5725);
DISPLAY 0.617021 (-7475 5725);
PAINT AQUA (-7475 5725);
FORCEPROP 1 LASTPIN (-7525 5675) $PN 1
J 0
(-7515 5655);
DISPLAY 0.617021 (-7515 5655);
PAINT MONO (-7515 5655);
FORCEPROP 1 LASTPIN (-7525 5475) $PN 2
J 0
(-7515 5455);
DISPLAY 0.617021 (-7515 5455);
PAINT MONO (-7515 5455);
FORCEPROP 2 LAST CDS_LIB pure_quanta
J 0
(-7525 5575);
DISPLAY INVISIBLE (-7525 5575);
FORCEPROP 1 LAST PATH I51
J 0
(-7475 5725);
DISPLAY 0.978723 (-7475 5725);
PAINT WHITE (-7475 5725);
DISPLAY INVISIBLE (-7475 5725);
FORCEPROP 1 LAST LOCATION PC399_P1_1
J 0
(-7475 5775);
DISPLAY 1.021277 (-7475 5775);
PAINT AQUA (-7475 5775);
DISPLAY INVISIBLE (-7475 5775);
FORCEPROP 0 LAST $SEC 1
J 0
(-7475 5775);
DISPLAY 0.680851 (-7475 5775);
PAINT MONO (-7475 5775);
DISPLAY INVISIBLE (-7475 5775);
FORCEPROP 0 LAST CDS_SEC 1
J 0
(-7475 5775);
DISPLAY 1.021277 (-7475 5775);
DISPLAY INVISIBLE (-7475 5775);
FORCEADD Q_CAP..1
(-7125 5575);
FORCEPROP 1 LAST PART_NUMBER CH6223MEA01
J 0
(-7075 5425);
DISPLAY 0.617021 (-7075 5425);
PAINT BLUE (-7075 5425);
DISPLAY INVISIBLE (-7075 5425);
FORCEPROP 1 LAST TOLERANCE 20%
J 0
(-7075 5575);
DISPLAY 0.617021 (-7075 5575);
PAINT SKYBLUE (-7075 5575);
FORCEPROP 1 LAST MATERIAL X6S
J 0
(-7075 5525);
DISPLAY 0.617021 (-7075 5525);
PAINT SKYBLUE (-7075 5525);
FORCEPROP 1 LAST PACK_TYPE C0805
J 0
(-7075 5475);
DISPLAY 0.617021 (-7075 5475);
PAINT SKYBLUE (-7075 5475);
FORCEPROP 1 LAST VALUE 22UF
J 0
(-7075 5675);
DISPLAY 0.617021 (-7075 5675);
PAINT SKYBLUE (-7075 5675);
FORCEPROP 1 LAST VOLTAGE 16V
J 0
(-7075 5625);
DISPLAY 0.617021 (-7075 5625);
PAINT SKYBLUE (-7075 5625);
FORCEPROP 1 LAST LOCATION PC403_P1_1
J 0
(-7075 5725);
DISPLAY 0.617021 (-7075 5725);
PAINT AQUA (-7075 5725);
FORCEPROP 1 LASTPIN (-7125 5675) $PN 1
J 0
(-7115 5655);
DISPLAY 0.617021 (-7115 5655);
PAINT MONO (-7115 5655);
FORCEPROP 1 LASTPIN (-7125 5475) $PN 2
J 0
(-7115 5455);
DISPLAY 0.617021 (-7115 5455);
PAINT MONO (-7115 5455);
FORCEPROP 2 LAST CDS_LIB pure_quanta
J 0
(-7125 5575);
DISPLAY INVISIBLE (-7125 5575);
FORCEPROP 1 LAST PATH I52
J 0
(-7075 5725);
DISPLAY 0.978723 (-7075 5725);
PAINT WHITE (-7075 5725);
DISPLAY INVISIBLE (-7075 5725);
FORCEPROP 1 LAST LOCATION PC403_P1_1
J 0
(-7075 5775);
DISPLAY 1.021277 (-7075 5775);
PAINT AQUA (-7075 5775);
DISPLAY INVISIBLE (-7075 5775);
FORCEPROP 0 LAST $SEC 1
J 0
(-7075 5775);
DISPLAY 0.680851 (-7075 5775);
PAINT MONO (-7075 5775);
DISPLAY INVISIBLE (-7075 5775);
FORCEPROP 0 LAST CDS_SEC 1
J 0
(-7075 5775);
DISPLAY 1.021277 (-7075 5775);
DISPLAY INVISIBLE (-7075 5775);
FORCEADD Q_RES..1
(-6025 4425);
FORCEPROP 1 LAST PART_NUMBER CS00002JB13
J 0
(-6125 4375);
DISPLAY 0.617021 (-6125 4375);
PAINT BLUE (-6125 4375);
DISPLAY INVISIBLE (-6125 4375);
FORCEPROP 1 LAST WATTAGE 1/16W
J 2
(-5800 4325);
DISPLAY 0.617021 (-5800 4325);
PAINT SKYBLUE (-5800 4325);
FORCEPROP 1 LAST TOLERANCE 5%
J 0
(-5850 4425);
DISPLAY 0.617021 (-5850 4425);
PAINT SKYBLUE (-5850 4425);
FORCEPROP 1 LAST VALUE 0
J 2
(-5875 4425);
DISPLAY 0.617021 (-5875 4425);
PAINT SKYBLUE (-5875 4425);
FORCEPROP 1 LAST PACK_TYPE 0402LF
J 0
(-6025 4325);
DISPLAY 0.617021 (-6025 4325);
PAINT SKYBLUE (-6025 4325);
FORCEPROP 1 LAST MATERIAL CHIP
J 0
(-6125 4325);
DISPLAY 0.617021 (-6125 4325);
PAINT SKYBLUE (-6125 4325);
FORCEPROP 1 LAST LOCATION PR1331
J 0
(-6275 4425);
DISPLAY 0.617021 (-6275 4425);
PAINT AQUA (-6275 4425);
FORCEPROP 1 LASTPIN (-6125 4425) $PN 1
J 0
(-6113 4437);
DISPLAY 0.617021 (-6113 4437);
FORCEPROP 1 LASTPIN (-5925 4425) $PN 2
J 0
(-5963 4437);
DISPLAY 0.617021 (-5963 4437);
FORCEPROP 2 LAST CDS_LIB pure_quanta
J 0
(-6025 4425);
PAINT MONO (-6025 4425);
DISPLAY INVISIBLE (-6025 4425);
FORCEPROP 1 LAST PATH I53
J 0
(-6075 4575);
DISPLAY 0.978723 (-6075 4575);
PAINT WHITE (-6075 4575);
DISPLAY INVISIBLE (-6075 4575);
FORCEPROP 2 LAST $SEC 1
J 0
(-6075 4625);
DISPLAY 0.680851 (-6075 4625);
PAINT MONO (-6075 4625);
DISPLAY INVISIBLE (-6075 4625);
FORCEPROP 2 LAST CDS_SEC 1
J 0
(-6075 4625);
DISPLAY 1.021277 (-6075 4625);
DISPLAY INVISIBLE (-6075 4625);
FORCEADD Q_CAP..1
R 2
(-6300 4950);
FORCEPROP 1 LAST PART_NUMBER CH4106K1B01
J 2
(-6350 4900);
DISPLAY 0.617021 (-6350 4900);
PAINT BLUE (-6350 4900);
DISPLAY INVISIBLE (-6350 4900);
FORCEPROP 1 LAST VALUE 100NF
J 2
(-6350 5000);
DISPLAY 0.617021 (-6350 5000);
PAINT SKYBLUE (-6350 5000);
FORCEPROP 1 LAST MATERIAL X7R
J 2
(-6350 4925);
DISPLAY 0.617021 (-6350 4925);
PAINT SKYBLUE (-6350 4925);
FORCEPROP 1 LAST TOLERANCE 10%
J 2
(-6350 4950);
DISPLAY 0.617021 (-6350 4950);
PAINT SKYBLUE (-6350 4950);
FORCEPROP 1 LAST VOLTAGE 50V
J 2
(-6350 4975);
DISPLAY 0.617021 (-6350 4975);
PAINT SKYBLUE (-6350 4975);
FORCEPROP 1 LAST PACK_TYPE C0402
J 2
(-6350 4875);
DISPLAY 0.617021 (-6350 4875);
PAINT SKYBLUE (-6350 4875);
FORCEPROP 1 LAST LOCATION PC401
J 2
(-6350 5025);
DISPLAY 0.617021 (-6350 5025);
PAINT AQUA (-6350 5025);
FORCEPROP 1 LASTPIN (-6300 5050) $PN 1
J 2
(-6310 5030);
DISPLAY 0.617021 (-6310 5030);
FORCEPROP 1 LASTPIN (-6300 4850) $PN 2
J 2
(-6310 4830);
DISPLAY 0.617021 (-6310 4830);
FORCEPROP 2 LAST CDS_LIB pure_quanta
J 2
(-6300 4950);
PAINT MONO (-6300 4950);
DISPLAY INVISIBLE (-6300 4950);
FORCEPROP 1 LAST PATH I54
J 2
(-6350 5100);
DISPLAY 0.978723 (-6350 5100);
PAINT WHITE (-6350 5100);
DISPLAY INVISIBLE (-6350 5100);
FORCEPROP 2 LAST $SEC 1
J 0
(-6350 5150);
DISPLAY 0.680851 (-6350 5150);
PAINT MONO (-6350 5150);
DISPLAY INVISIBLE (-6350 5150);
FORCEPROP 2 LAST CDS_SEC 1
J 0
(-6350 5150);
DISPLAY 1.021277 (-6350 5150);
DISPLAY INVISIBLE (-6350 5150);
FORCEADD Q_INDUCTOR..1
(-6025 4700);
FORCEPROP 1 LAST PART_NUMBER CV+13^0KZ11
J 0
(-6150 4810);
DISPLAY 0.617021 (-6150 4810);
PAINT BLUE (-6150 4810);
DISPLAY INVISIBLE (-6150 4810);
FORCEPROP 1 LAST MATERIAL IND
J 0
(-6150 4755);
DISPLAY 0.617021 (-6150 4755);
PAINT SKYBLUE (-6150 4755);
FORCEPROP 2 LAST PACK_TYPE SMLF
J 0
(-6150 4900);
DISPLAY 0.617021 (-6150 4900);
PAINT SKYBLUE (-6150 4900);
FORCEPROP 2 LAST VALUE 130NH/106A
J 0
(-6150 4950);
DISPLAY 0.617021 (-6150 4950);
PAINT SKYBLUE (-6150 4950);
FORCEPROP 1 LAST LOCATION PL18
J 0
(-6150 4860);
DISPLAY 0.617021 (-6150 4860);
PAINT AQUA (-6150 4860);
FORCEPROP 0 LASTPIN (-6125 4675) $PN 1
J 2
(-6135 4685);
DISPLAY 0.617021 (-6135 4685);
PAINT MONO (-6135 4685);
FORCEPROP 0 LASTPIN (-5925 4675) $PN 2
J 0
(-5915 4685);
DISPLAY 0.617021 (-5915 4685);
PAINT MONO (-5915 4685);
FORCEPROP 2 LAST CDS_LIB pure_quanta
J 0
(-6025 4700);
DISPLAY INVISIBLE (-6025 4700);
FORCEPROP 1 LAST NEEDS_NO_SIZE TRUE
J 0
(-6025 4700);
DISPLAY 0.468085 (-6025 4700);
PAINT GREEN (-6025 4700);
DISPLAY INVISIBLE (-6025 4700);
FORCEPROP 1 LAST PATH I55
J 0
(-5950 4755);
DISPLAY 0.723404 (-5950 4755);
PAINT GREEN (-5950 4755);
DISPLAY INVISIBLE (-5950 4755);
FORCEPROP 0 LAST $SEC 1
J 0
(-6150 5000);
DISPLAY 0.680851 (-6150 5000);
PAINT MONO (-6150 5000);
DISPLAY INVISIBLE (-6150 5000);
FORCEPROP 0 LAST CDS_SEC 1
J 0
(-6150 5000);
DISPLAY 1.021277 (-6150 5000);
DISPLAY INVISIBLE (-6150 5000);
FORCEADD Q_CAP..1
(-6725 5575);
FORCEPROP 1 LAST PART_NUMBER CH6223MEA01
J 0
(-6675 5425);
DISPLAY 0.617021 (-6675 5425);
PAINT BLUE (-6675 5425);
DISPLAY INVISIBLE (-6675 5425);
FORCEPROP 1 LAST TOLERANCE 20%
J 0
(-6675 5575);
DISPLAY 0.617021 (-6675 5575);
PAINT SKYBLUE (-6675 5575);
FORCEPROP 1 LAST VOLTAGE 16V
J 0
(-6675 5625);
DISPLAY 0.617021 (-6675 5625);
PAINT SKYBLUE (-6675 5625);
FORCEPROP 1 LAST PACK_TYPE C0805
J 0
(-6675 5475);
DISPLAY 0.617021 (-6675 5475);
PAINT SKYBLUE (-6675 5475);
FORCEPROP 1 LAST VALUE 22UF
J 0
(-6675 5675);
DISPLAY 0.617021 (-6675 5675);
PAINT SKYBLUE (-6675 5675);
FORCEPROP 1 LAST MATERIAL X6S
J 0
(-6675 5525);
DISPLAY 0.617021 (-6675 5525);
PAINT SKYBLUE (-6675 5525);
FORCEPROP 1 LAST LOCATION PC405_P1_1
J 0
(-6675 5725);
DISPLAY 0.617021 (-6675 5725);
PAINT AQUA (-6675 5725);
FORCEPROP 1 LASTPIN (-6725 5675) $PN 1
J 0
(-6715 5655);
DISPLAY 0.617021 (-6715 5655);
PAINT MONO (-6715 5655);
FORCEPROP 1 LASTPIN (-6725 5475) $PN 2
J 0
(-6715 5455);
DISPLAY 0.617021 (-6715 5455);
PAINT MONO (-6715 5455);
FORCEPROP 2 LAST CDS_LIB pure_quanta
J 0
(-6725 5575);
DISPLAY INVISIBLE (-6725 5575);
FORCEPROP 1 LAST PATH I56
J 0
(-6675 5725);
DISPLAY 0.978723 (-6675 5725);
PAINT WHITE (-6675 5725);
DISPLAY INVISIBLE (-6675 5725);
FORCEPROP 1 LAST LOCATION PC405_P1_1
J 0
(-6675 5775);
DISPLAY 1.021277 (-6675 5775);
PAINT AQUA (-6675 5775);
DISPLAY INVISIBLE (-6675 5775);
FORCEPROP 0 LAST $SEC 1
J 0
(-6675 5775);
DISPLAY 0.680851 (-6675 5775);
PAINT MONO (-6675 5775);
DISPLAY INVISIBLE (-6675 5775);
FORCEPROP 0 LAST CDS_SEC 1
J 0
(-6675 5775);
DISPLAY 1.021277 (-6675 5775);
DISPLAY INVISIBLE (-6675 5775);
FORCEADD UNIVERSAL_GND..1
(-6125 5200);
FORCEPROP 3 LASTPIN (-6125 5250) SIG_NAME GND\g
J 0
(-6115 5260);
DISPLAY 0.659574 (-6115 5260);
PAINT MONO (-6115 5260);
DISPLAY INVISIBLE (-6115 5260);
FORCEPROP 1 LAST HDL_POWER GND
J 1
(-6100 5125);
DISPLAY 0.872340 (-6100 5125);
PAINT GREEN (-6100 5125);
DISPLAY INVISIBLE (-6100 5125);
FORCEPROP 2 LAST CDS_LIB logical_power
J 0
(-6125 5200);
PAINT MONO (-6125 5200);
DISPLAY INVISIBLE (-6125 5200);
FORCEPROP 1 LAST PATH I57
J 0
(-6050 5200);
DISPLAY 0.872340 (-6050 5200);
PAINT AQUA (-6050 5200);
DISPLAY INVISIBLE (-6050 5200);
FORCEADD Q_CAP..1
(-6275 5575);
FORCEPROP 1 LAST PART_NUMBER CH6223MEA01
J 0
(-6225 5425);
DISPLAY 0.617021 (-6225 5425);
PAINT BLUE (-6225 5425);
DISPLAY INVISIBLE (-6225 5425);
FORCEPROP 1 LAST TOLERANCE 20%
J 0
(-6225 5575);
DISPLAY 0.617021 (-6225 5575);
PAINT SKYBLUE (-6225 5575);
FORCEPROP 1 LAST PACK_TYPE C0805
J 0
(-6225 5475);
DISPLAY 0.617021 (-6225 5475);
PAINT SKYBLUE (-6225 5475);
FORCEPROP 1 LAST MATERIAL X6S
J 0
(-6225 5525);
DISPLAY 0.617021 (-6225 5525);
PAINT SKYBLUE (-6225 5525);
FORCEPROP 1 LAST VALUE 22UF
J 0
(-6225 5675);
DISPLAY 0.617021 (-6225 5675);
PAINT SKYBLUE (-6225 5675);
FORCEPROP 1 LAST VOLTAGE 16V
J 0
(-6225 5625);
DISPLAY 0.617021 (-6225 5625);
PAINT SKYBLUE (-6225 5625);
FORCEPROP 1 LAST LOCATION PC724_P1_1
J 0
(-6225 5725);
DISPLAY 0.617021 (-6225 5725);
PAINT AQUA (-6225 5725);
FORCEPROP 1 LASTPIN (-6275 5675) $PN 1
J 0
(-6265 5655);
DISPLAY 0.787234 (-6265 5655);
PAINT MONO (-6265 5655);
FORCEPROP 1 LASTPIN (-6275 5475) $PN 2
J 0
(-6265 5455);
DISPLAY 0.787234 (-6265 5455);
PAINT MONO (-6265 5455);
FORCEPROP 2 LAST CDS_LIB pure_quanta
J 0
(-6275 5575);
DISPLAY INVISIBLE (-6275 5575);
FORCEPROP 1 LAST PATH I58
J 0
(-6225 5725);
DISPLAY 0.978723 (-6225 5725);
PAINT WHITE (-6225 5725);
DISPLAY INVISIBLE (-6225 5725);
FORCEPROP 0 LAST $SEC 1
J 0
(-6225 5725);
DISPLAY 0.680851 (-6225 5725);
PAINT MONO (-6225 5725);
DISPLAY INVISIBLE (-6225 5725);
FORCEPROP 0 LAST CDS_SEC 1
J 0
(-6225 5725);
DISPLAY 1.021277 (-6225 5725);
DISPLAY INVISIBLE (-6225 5725);
FORCEADD VCC15..1
(-6125 5950);
FORCEPROP 3 LASTPIN (-6125 5900) SIG_NAME SW_P12V_PVCCFA_EHV_FIVRA_CPU1_R\g
J 0
(-6115 5910);
DISPLAY 0.659574 (-6115 5910);
PAINT MONO (-6115 5910);
DISPLAY INVISIBLE (-6115 5910);
FORCEPROP 1 LAST HDL_POWER SW_P12V_PVCCFA_EHV_FIVRA_CPU1_R
J 1
(-6075 6000);
DISPLAY 0.617021 (-6075 6000);
PAINT GREEN (-6075 6000);
FORCEPROP 2 LAST CDS_LIB logical_power
J 0
(-6125 5950);
DISPLAY INVISIBLE (-6125 5950);
FORCEPROP 1 LAST PATH I59
J 0
(-6075 5975);
DISPLAY 0.872340 (-6075 5975);
PAINT AQUA (-6075 5975);
DISPLAY INVISIBLE (-6075 5975);
FORCEADD OFFPAGE..5
(-10275 1375);
FORCEPROP 2 LAST $XR2 284 
J 0
(-10530 1411);
DISPLAY 0.638298 (-10530 1411);
PAINT MONO (-10530 1411);
FORCEPROP 2 LAST $XR1 290 
J 0
(-10530 1339);
DISPLAY 0.638298 (-10530 1339);
PAINT MONO (-10530 1339);
FORCEPROP 2 LAST $XR0 289 
J 0
(-10530 1375);
DISPLAY 0.638298 (-10530 1375);
PAINT MONO (-10530 1375);
FORCEPROP 1 LAST COMMENT_BODY TRUE
J 0
(-10175 1300);
DISPLAY 0.872340 (-10175 1300);
PAINT GREEN (-10175 1300);
DISPLAY INVISIBLE (-10175 1300);
FORCEPROP 1 LAST OFFPAGE TRUE
J 0
(-9950 1250);
DISPLAY 0.872340 (-9950 1250);
PAINT GREEN (-9950 1250);
DISPLAY INVISIBLE (-9950 1250);
FORCEPROP 2 LAST CDS_LIB standard
J 0
(-10275 1375);
DISPLAY INVISIBLE (-10275 1375);
FORCEPROP 2 LAST PATH I6
J 0
(-10525 1450);
DISPLAY 1.021277 (-10525 1450);
DISPLAY INVISIBLE (-10525 1450);
FORCEADD Q_CAP..1
(-5050 4475);
FORCEPROP 1 LAST PART_NUMBER CH4106K1B01
J 0
(-5000 4300);
DISPLAY 0.617021 (-5000 4300);
PAINT BLUE (-5000 4300);
DISPLAY INVISIBLE (-5000 4300);
FORCEPROP 1 LAST MATERIAL X7R
J 0
(-5000 4400);
DISPLAY 0.617021 (-5000 4400);
PAINT SKYBLUE (-5000 4400);
FORCEPROP 1 LAST VOLTAGE 50V
J 0
(-5000 4500);
DISPLAY 0.617021 (-5000 4500);
PAINT SKYBLUE (-5000 4500);
FORCEPROP 1 LAST VALUE 100NF
J 0
(-5000 4550);
DISPLAY 0.617021 (-5000 4550);
PAINT SKYBLUE (-5000 4550);
FORCEPROP 1 LAST PACK_TYPE C0402
J 0
(-5000 4350);
DISPLAY 0.617021 (-5000 4350);
PAINT SKYBLUE (-5000 4350);
FORCEPROP 1 LAST TOLERANCE 10%
J 0
(-5000 4450);
DISPLAY 0.617021 (-5000 4450);
PAINT SKYBLUE (-5000 4450);
FORCEPROP 1 LAST LOCATION PC621_P1_1
J 0
(-5000 4600);
DISPLAY 0.617021 (-5000 4600);
PAINT AQUA (-5000 4600);
FORCEPROP 2 LAST CDS_LIB pure_quanta
J 0
(-5050 4475);
DISPLAY INVISIBLE (-5050 4475);
FORCEPROP 1 LAST PATH I60
J 0
(-5000 4625);
DISPLAY 0.978723 (-5000 4625);
PAINT WHITE (-5000 4625);
DISPLAY INVISIBLE (-5000 4625);
FORCEPROP 1 LAST LOCATION PC621_P1_1
J 0
(-5000 4650);
DISPLAY 1.021277 (-5000 4650);
PAINT AQUA (-5000 4650);
DISPLAY INVISIBLE (-5000 4650);
FORCEPROP 0 LAST $SEC 1
J 0
(-5000 4650);
DISPLAY 0.680851 (-5000 4650);
PAINT MONO (-5000 4650);
DISPLAY INVISIBLE (-5000 4650);
FORCEPROP 0 LAST CDS_SEC 1
J 0
(-5000 4650);
DISPLAY 1.021277 (-5000 4650);
DISPLAY INVISIBLE (-5000 4650);
FORCEPROP 1 LASTPIN (-5050 4575) $PN 1
J 0
(-5040 4555);
DISPLAY 0.787234 (-5040 4555);
PAINT MONO (-5040 4555);
DISPLAY INVISIBLE (-5040 4555);
FORCEPROP 1 LASTPIN (-5050 4375) $PN 2
J 0
(-5040 4355);
DISPLAY 0.787234 (-5040 4355);
PAINT MONO (-5040 4355);
DISPLAY INVISIBLE (-5040 4355);
FORCEADD Q_CAP..1
(-4975 1675);
FORCEPROP 1 LAST PART_NUMBER CH5103KEB01
J 0
(-4925 1500);
DISPLAY 0.617021 (-4925 1500);
PAINT BLUE (-4925 1500);
DISPLAY INVISIBLE (-4925 1500);
FORCEPROP 1 LAST MATERIAL X6S
J 0
(-4925 1600);
DISPLAY 0.617021 (-4925 1600);
PAINT SKYBLUE (-4925 1600);
FORCEPROP 1 LAST TOLERANCE 10%
J 0
(-4925 1650);
DISPLAY 0.617021 (-4925 1650);
PAINT SKYBLUE (-4925 1650);
FORCEPROP 1 LAST VALUE 1UF
J 0
(-4925 1750);
DISPLAY 0.617021 (-4925 1750);
PAINT SKYBLUE (-4925 1750);
FORCEPROP 1 LAST VOLTAGE 16V
J 0
(-4925 1700);
DISPLAY 0.617021 (-4925 1700);
PAINT SKYBLUE (-4925 1700);
FORCEPROP 1 LAST PACK_TYPE C0402
J 0
(-4925 1550);
DISPLAY 0.617021 (-4925 1550);
PAINT SKYBLUE (-4925 1550);
FORCEPROP 1 LAST LOCATION PC408_P1_2
J 0
(-4925 1800);
DISPLAY 0.617021 (-4925 1800);
PAINT AQUA (-4925 1800);
FORCEPROP 2 LAST CDS_LIB pure_quanta
J 0
(-4975 1675);
DISPLAY INVISIBLE (-4975 1675);
FORCEPROP 1 LAST PATH I61
J 0
(-4925 1825);
DISPLAY 0.978723 (-4925 1825);
PAINT WHITE (-4925 1825);
DISPLAY INVISIBLE (-4925 1825);
FORCEPROP 1 LAST LOCATION PC408_P1_2
J 0
(-4925 1850);
DISPLAY 1.021277 (-4925 1850);
PAINT AQUA (-4925 1850);
DISPLAY INVISIBLE (-4925 1850);
FORCEPROP 0 LAST $SEC 1
J 0
(-4925 1850);
DISPLAY 0.680851 (-4925 1850);
PAINT MONO (-4925 1850);
DISPLAY INVISIBLE (-4925 1850);
FORCEPROP 0 LAST CDS_SEC 1
J 0
(-4925 1850);
DISPLAY 1.021277 (-4925 1850);
DISPLAY INVISIBLE (-4925 1850);
FORCEPROP 1 LASTPIN (-4975 1775) $PN 1
J 0
(-4965 1755);
DISPLAY 0.787234 (-4965 1755);
PAINT MONO (-4965 1755);
DISPLAY INVISIBLE (-4965 1755);
FORCEPROP 1 LASTPIN (-4975 1575) $PN 2
J 0
(-4965 1555);
DISPLAY 0.787234 (-4965 1555);
PAINT MONO (-4965 1555);
DISPLAY INVISIBLE (-4965 1555);
FORCEADD Q_CAP..1
(-4550 1675);
FORCEPROP 1 LAST PART_NUMBER CH622KMEA03
J 0
(-4500 1500);
DISPLAY 0.617021 (-4500 1500);
PAINT BLUE (-4500 1500);
DISPLAY INVISIBLE (-4500 1500);
FORCEPROP 1 LAST TOLERANCE 20%
J 0
(-4500 1650);
DISPLAY 0.617021 (-4500 1650);
PAINT SKYBLUE (-4500 1650);
FORCEPROP 1 LAST PACK_TYPE C0805
J 0
(-4500 1550);
DISPLAY 0.617021 (-4500 1550);
PAINT SKYBLUE (-4500 1550);
FORCEPROP 1 LAST VOLTAGE 4V
J 0
(-4500 1700);
DISPLAY 0.617021 (-4500 1700);
PAINT SKYBLUE (-4500 1700);
FORCEPROP 1 LAST VALUE 22UF
J 0
(-4500 1750);
DISPLAY 0.617021 (-4500 1750);
PAINT SKYBLUE (-4500 1750);
FORCEPROP 1 LAST MATERIAL X6S
J 0
(-4500 1600);
DISPLAY 0.617021 (-4500 1600);
PAINT SKYBLUE (-4500 1600);
FORCEPROP 1 LAST LOCATION PC411_P1_2
J 0
(-4500 1800);
DISPLAY 0.617021 (-4500 1800);
PAINT AQUA (-4500 1800);
FORCEPROP 1 LASTPIN (-4550 1775) $PN 1
J 0
(-4540 1755);
DISPLAY 0.617021 (-4540 1755);
PAINT MONO (-4540 1755);
FORCEPROP 1 LASTPIN (-4550 1575) $PN 2
J 0
(-4540 1555);
DISPLAY 0.617021 (-4540 1555);
PAINT MONO (-4540 1555);
FORCEPROP 2 LAST CDS_LIB pure_quanta
J 0
(-4550 1675);
DISPLAY INVISIBLE (-4550 1675);
FORCEPROP 1 LAST PATH I62
J 0
(-4500 1825);
DISPLAY 0.978723 (-4500 1825);
PAINT WHITE (-4500 1825);
DISPLAY INVISIBLE (-4500 1825);
FORCEPROP 1 LAST LOCATION PC411_P1_2
J 0
(-4500 1850);
DISPLAY 1.021277 (-4500 1850);
PAINT AQUA (-4500 1850);
DISPLAY INVISIBLE (-4500 1850);
FORCEPROP 0 LAST $SEC 1
J 0
(-4500 1850);
DISPLAY 0.680851 (-4500 1850);
PAINT MONO (-4500 1850);
DISPLAY INVISIBLE (-4500 1850);
FORCEPROP 0 LAST CDS_SEC 1
J 0
(-4500 1850);
DISPLAY 1.021277 (-4500 1850);
DISPLAY INVISIBLE (-4500 1850);
FORCEADD Q_CAP..1
(-4125 1675);
FORCEPROP 1 LAST PART_NUMBER CH622KMEA03
J 0
(-4075 1500);
DISPLAY 0.617021 (-4075 1500);
PAINT BLUE (-4075 1500);
DISPLAY INVISIBLE (-4075 1500);
FORCEPROP 1 LAST TOLERANCE 20%
J 0
(-4075 1650);
DISPLAY 0.617021 (-4075 1650);
PAINT SKYBLUE (-4075 1650);
FORCEPROP 1 LAST PACK_TYPE C0805
J 0
(-4075 1550);
DISPLAY 0.617021 (-4075 1550);
PAINT SKYBLUE (-4075 1550);
FORCEPROP 1 LAST VOLTAGE 4V
J 0
(-4075 1700);
DISPLAY 0.617021 (-4075 1700);
PAINT SKYBLUE (-4075 1700);
FORCEPROP 1 LAST MATERIAL X6S
J 0
(-4075 1600);
DISPLAY 0.617021 (-4075 1600);
PAINT SKYBLUE (-4075 1600);
FORCEPROP 1 LAST VALUE 22UF
J 0
(-4075 1750);
DISPLAY 0.617021 (-4075 1750);
PAINT SKYBLUE (-4075 1750);
FORCEPROP 1 LAST LOCATION PC413_P1_2
J 0
(-4075 1800);
DISPLAY 0.617021 (-4075 1800);
PAINT AQUA (-4075 1800);
FORCEPROP 1 LASTPIN (-4125 1775) $PN 1
J 0
(-4115 1755);
DISPLAY 0.617021 (-4115 1755);
PAINT MONO (-4115 1755);
FORCEPROP 1 LASTPIN (-4125 1575) $PN 2
J 0
(-4115 1555);
DISPLAY 0.617021 (-4115 1555);
PAINT MONO (-4115 1555);
FORCEPROP 2 LAST CDS_LIB pure_quanta
J 0
(-4125 1675);
DISPLAY INVISIBLE (-4125 1675);
FORCEPROP 1 LAST PATH I63
J 0
(-4075 1825);
DISPLAY 0.978723 (-4075 1825);
PAINT WHITE (-4075 1825);
DISPLAY INVISIBLE (-4075 1825);
FORCEPROP 1 LAST LOCATION PC413_P1_2
J 0
(-4075 1850);
DISPLAY 1.021277 (-4075 1850);
PAINT AQUA (-4075 1850);
DISPLAY INVISIBLE (-4075 1850);
FORCEPROP 0 LAST $SEC 1
J 0
(-4075 1850);
DISPLAY 0.680851 (-4075 1850);
PAINT MONO (-4075 1850);
DISPLAY INVISIBLE (-4075 1850);
FORCEPROP 0 LAST CDS_SEC 1
J 0
(-4075 1850);
DISPLAY 1.021277 (-4075 1850);
DISPLAY INVISIBLE (-4075 1850);
FORCEADD Q_RES..2
(-3650 1675);
FORCEPROP 1 LAST PART_NUMBER CS14992FB06
J 0
(-3610 1550);
DISPLAY 0.617021 (-3610 1550);
PAINT BLUE (-3610 1550);
DISPLAY INVISIBLE (-3610 1550);
FORCEPROP 1 LAST PACK_TYPE 0402LF
J 0
(-3610 1500);
DISPLAY 0.617021 (-3610 1500);
PAINT SKYBLUE (-3610 1500);
FORCEPROP 1 LAST MATERIAL CHIP
J 0
(-3610 1600);
DISPLAY 0.617021 (-3610 1600);
PAINT SKYBLUE (-3610 1600);
FORCEPROP 1 LAST WATTAGE 1/16W
J 0
(-3610 1650);
DISPLAY 0.617021 (-3610 1650);
PAINT SKYBLUE (-3610 1650);
FORCEPROP 1 LAST TOLERANCE 1%
J 0
(-3605 1700);
DISPLAY 0.617021 (-3605 1700);
PAINT SKYBLUE (-3605 1700);
FORCEPROP 1 LAST VALUE 499
J 0
(-3605 1750);
DISPLAY 0.617021 (-3605 1750);
PAINT SKYBLUE (-3605 1750);
FORCEPROP 1 LAST LOCATION PR4241
J 0
(-3605 1800);
DISPLAY 0.617021 (-3605 1800);
PAINT AQUA (-3605 1800);
FORCEPROP 1 LASTPIN (-3650 1775) $PN 1
J 0
(-3645 1737);
DISPLAY 0.787234 (-3645 1737);
PAINT MONO (-3645 1737);
FORCEPROP 1 LASTPIN (-3650 1575) $PN 2
J 0
(-3645 1585);
DISPLAY 0.787234 (-3645 1585);
PAINT MONO (-3645 1585);
FORCEPROP 2 LAST BOM_COST VR_PCH
J 0
(-3600 1850);
DISPLAY 0.680851 (-3600 1850);
DISPLAY INVISIBLE (-3600 1850);
FORCEPROP 2 LAST CDS_LIB pure_quanta
J 0
(-3650 1675);
DISPLAY INVISIBLE (-3650 1675);
FORCEPROP 1 LAST PATH I64
J 0
(-3600 1850);
DISPLAY 0.978723 (-3600 1850);
PAINT WHITE (-3600 1850);
DISPLAY INVISIBLE (-3600 1850);
FORCEPROP 0 LAST $SEC 1
J 0
(-3600 1850);
DISPLAY 0.680851 (-3600 1850);
PAINT MONO (-3600 1850);
DISPLAY INVISIBLE (-3600 1850);
FORCEPROP 0 LAST CDS_SEC 1
J 0
(-3600 1850);
DISPLAY 1.021277 (-3600 1850);
DISPLAY INVISIBLE (-3600 1850);
FORCEADD UNIVERSAL_GND..1
(-3300 1325);
FORCEPROP 3 LASTPIN (-3300 1375) SIG_NAME GND\g
J 0
(-3290 1385);
DISPLAY 0.659574 (-3290 1385);
PAINT MONO (-3290 1385);
DISPLAY INVISIBLE (-3290 1385);
FORCEPROP 1 LAST HDL_POWER GND
J 1
(-3275 1250);
DISPLAY 0.872340 (-3275 1250);
PAINT GREEN (-3275 1250);
DISPLAY INVISIBLE (-3275 1250);
FORCEPROP 2 LAST CDS_LIB logical_power
J 0
(-3300 1325);
PAINT MONO (-3300 1325);
DISPLAY INVISIBLE (-3300 1325);
FORCEPROP 1 LAST PATH I65
J 0
(-3225 1325);
DISPLAY 0.872340 (-3225 1325);
PAINT AQUA (-3225 1325);
DISPLAY INVISIBLE (-3225 1325);
FORCEADD Q_CAPP..1
(-4825 2800);
FORCEPROP 1 LAST PART_NUMBER CC7560JMD16
J 0
(-4775 2650);
DISPLAY 0.617021 (-4775 2650);
PAINT BLUE (-4775 2650);
DISPLAY INVISIBLE (-4775 2650);
FORCEPROP 1 LAST PACK_TYPE THLF
J 0
(-4775 2700);
DISPLAY 0.617021 (-4775 2700);
PAINT SKYBLUE (-4775 2700);
FORCEPROP 1 LAST VALUE 560UF
J 0
(-4775 2900);
DISPLAY 0.617021 (-4775 2900);
PAINT SKYBLUE (-4775 2900);
FORCEPROP 1 LAST TOLERANCE 20%
J 0
(-4775 2850);
DISPLAY 0.617021 (-4775 2850);
PAINT SKYBLUE (-4775 2850);
FORCEPROP 1 LAST MATERIAL OSCON
J 0
(-4775 2750);
DISPLAY 0.617021 (-4775 2750);
PAINT SKYBLUE (-4775 2750);
FORCEPROP 1 LAST VOLTAGE 2.5V
J 0
(-4775 2800);
DISPLAY 0.617021 (-4775 2800);
PAINT SKYBLUE (-4775 2800);
FORCEPROP 1 LAST LOCATION PC414
J 0
(-4775 2950);
DISPLAY 0.617021 (-4775 2950);
PAINT AQUA (-4775 2950);
FORCEPROP 1 LASTPIN (-4825 2900) $PN 1
J 0
(-4815 2885);
DISPLAY 0.617021 (-4815 2885);
PAINT MONO (-4815 2885);
FORCEPROP 1 LASTPIN (-4825 2700) $PN 2
J 0
(-4815 2685);
DISPLAY 0.617021 (-4815 2685);
PAINT MONO (-4815 2685);
FORCEPROP 2 LAST CDS_LIB pure_quanta
J 0
(-4825 2800);
DISPLAY INVISIBLE (-4825 2800);
FORCEPROP 1 LAST PATH I66
J 0
(-4775 2950);
DISPLAY 0.978723 (-4775 2950);
DISPLAY INVISIBLE (-4775 2950);
FORCEPROP 1 LAST LOCATION PC414
J 0
(-4775 3000);
DISPLAY 1.021277 (-4775 3000);
PAINT AQUA (-4775 3000);
DISPLAY INVISIBLE (-4775 3000);
FORCEPROP 0 LAST $SEC 1
J 0
(-4775 3000);
DISPLAY 0.680851 (-4775 3000);
PAINT MONO (-4775 3000);
DISPLAY INVISIBLE (-4775 3000);
FORCEPROP 0 LAST CDS_SEC 1
J 0
(-4775 3000);
DISPLAY 1.021277 (-4775 3000);
DISPLAY INVISIBLE (-4775 3000);
FORCEADD Q_CAPP..1
(-4300 2800);
FORCEPROP 1 LAST PART_NUMBER CC7560JMD16
J 0
(-4250 2650);
DISPLAY 0.617021 (-4250 2650);
PAINT BLUE (-4250 2650);
DISPLAY INVISIBLE (-4250 2650);
FORCEPROP 1 LAST PACK_TYPE THLF
J 0
(-4250 2700);
DISPLAY 0.617021 (-4250 2700);
PAINT SKYBLUE (-4250 2700);
FORCEPROP 1 LAST VALUE 560UF
J 0
(-4250 2900);
DISPLAY 0.617021 (-4250 2900);
PAINT SKYBLUE (-4250 2900);
FORCEPROP 1 LAST TOLERANCE 20%
J 0
(-4250 2850);
DISPLAY 0.617021 (-4250 2850);
PAINT SKYBLUE (-4250 2850);
FORCEPROP 1 LAST MATERIAL OSCON
J 0
(-4250 2750);
DISPLAY 0.617021 (-4250 2750);
PAINT SKYBLUE (-4250 2750);
FORCEPROP 1 LAST VOLTAGE 2.5V
J 0
(-4250 2800);
DISPLAY 0.617021 (-4250 2800);
PAINT SKYBLUE (-4250 2800);
FORCEPROP 1 LAST LOCATION PC415
J 0
(-4250 2950);
DISPLAY 0.617021 (-4250 2950);
PAINT AQUA (-4250 2950);
FORCEPROP 1 LASTPIN (-4300 2900) $PN 1
J 0
(-4290 2885);
DISPLAY 0.617021 (-4290 2885);
PAINT MONO (-4290 2885);
FORCEPROP 1 LASTPIN (-4300 2700) $PN 2
J 0
(-4290 2685);
DISPLAY 0.617021 (-4290 2685);
PAINT MONO (-4290 2685);
FORCEPROP 2 LAST CDS_LIB pure_quanta
J 0
(-4300 2800);
DISPLAY INVISIBLE (-4300 2800);
FORCEPROP 1 LAST PATH I67
J 0
(-4250 2950);
DISPLAY 0.978723 (-4250 2950);
DISPLAY INVISIBLE (-4250 2950);
FORCEPROP 1 LAST LOCATION PC415
J 0
(-4250 3000);
DISPLAY 1.021277 (-4250 3000);
PAINT AQUA (-4250 3000);
DISPLAY INVISIBLE (-4250 3000);
FORCEPROP 0 LAST $SEC 1
J 0
(-4250 3000);
DISPLAY 0.680851 (-4250 3000);
PAINT MONO (-4250 3000);
DISPLAY INVISIBLE (-4250 3000);
FORCEPROP 0 LAST CDS_SEC 1
J 0
(-4250 3000);
DISPLAY 1.021277 (-4250 3000);
DISPLAY INVISIBLE (-4250 3000);
FORCEADD Q_CAPP..1
(-3775 2800);
FORCEPROP 1 LAST PART_NUMBER CC7560JMD16
J 0
(-3725 2650);
DISPLAY 0.617021 (-3725 2650);
PAINT BLUE (-3725 2650);
DISPLAY INVISIBLE (-3725 2650);
FORCEPROP 1 LAST PACK_TYPE THLF
J 0
(-3725 2700);
DISPLAY 0.617021 (-3725 2700);
PAINT SKYBLUE (-3725 2700);
FORCEPROP 1 LAST VALUE 560UF
J 0
(-3725 2900);
DISPLAY 0.617021 (-3725 2900);
PAINT SKYBLUE (-3725 2900);
FORCEPROP 1 LAST TOLERANCE 20%
J 0
(-3725 2850);
DISPLAY 0.617021 (-3725 2850);
PAINT SKYBLUE (-3725 2850);
FORCEPROP 1 LAST MATERIAL OSCON
J 0
(-3725 2750);
DISPLAY 0.617021 (-3725 2750);
PAINT SKYBLUE (-3725 2750);
FORCEPROP 1 LAST VOLTAGE 2.5V
J 0
(-3725 2800);
DISPLAY 0.617021 (-3725 2800);
PAINT SKYBLUE (-3725 2800);
FORCEPROP 1 LAST LOCATION PC416
J 0
(-3725 2950);
DISPLAY 0.617021 (-3725 2950);
PAINT AQUA (-3725 2950);
FORCEPROP 1 LASTPIN (-3775 2900) $PN 1
J 0
(-3765 2885);
DISPLAY 0.617021 (-3765 2885);
PAINT MONO (-3765 2885);
FORCEPROP 1 LASTPIN (-3775 2700) $PN 2
J 0
(-3765 2685);
DISPLAY 0.617021 (-3765 2685);
PAINT MONO (-3765 2685);
FORCEPROP 2 LAST CDS_LIB pure_quanta
J 0
(-3775 2800);
DISPLAY INVISIBLE (-3775 2800);
FORCEPROP 1 LAST PATH I68
J 0
(-3725 2950);
DISPLAY 0.978723 (-3725 2950);
DISPLAY INVISIBLE (-3725 2950);
FORCEPROP 1 LAST LOCATION PC416
J 0
(-3725 3000);
DISPLAY 1.021277 (-3725 3000);
PAINT AQUA (-3725 3000);
DISPLAY INVISIBLE (-3725 3000);
FORCEPROP 0 LAST $SEC 1
J 0
(-3725 3000);
DISPLAY 0.680851 (-3725 3000);
PAINT MONO (-3725 3000);
DISPLAY INVISIBLE (-3725 3000);
FORCEPROP 0 LAST CDS_SEC 1
J 0
(-3725 3000);
DISPLAY 1.021277 (-3725 3000);
DISPLAY INVISIBLE (-3725 3000);
FORCEADD VCC15..1
(-3300 2000);
FORCEPROP 3 LASTPIN (-3300 1950) SIG_NAME PVCCFA_EHV_FIVRA_CPU1\g
J 0
(-3290 1960);
DISPLAY 0.659574 (-3290 1960);
PAINT MONO (-3290 1960);
DISPLAY INVISIBLE (-3290 1960);
FORCEPROP 1 LAST HDL_POWER PVCCFA_EHV_FIVRA_CPU1
J 1
(-3300 2050);
DISPLAY 0.617021 (-3300 2050);
PAINT GREEN (-3300 2050);
FORCEPROP 2 LAST CDS_LIB logical_power
J 0
(-3300 2000);
DISPLAY INVISIBLE (-3300 2000);
FORCEPROP 1 LAST PATH I69
J 0
(-3250 2025);
DISPLAY 0.872340 (-3250 2025);
PAINT AQUA (-3250 2025);
DISPLAY INVISIBLE (-3250 2025);
FORCEADD OFFPAGE..5
(-10275 1875);
FORCEPROP 2 LAST $XR0 284 
J 0
(-10530 1875);
DISPLAY 0.638298 (-10530 1875);
PAINT MONO (-10530 1875);
FORCEPROP 1 LAST COMMENT_BODY TRUE
J 0
(-10175 1800);
DISPLAY 0.872340 (-10175 1800);
PAINT GREEN (-10175 1800);
DISPLAY INVISIBLE (-10175 1800);
FORCEPROP 1 LAST OFFPAGE TRUE
J 0
(-9950 1750);
DISPLAY 0.872340 (-9950 1750);
PAINT GREEN (-9950 1750);
DISPLAY INVISIBLE (-9950 1750);
FORCEPROP 2 LAST CDS_LIB standard
J 0
(-10275 1875);
DISPLAY INVISIBLE (-10275 1875);
FORCEPROP 2 LAST PATH I7
J 0
(-10525 1925);
DISPLAY 1.021277 (-10525 1925);
DISPLAY INVISIBLE (-10525 1925);
FORCEADD Q_CAPP..1
(-3275 2800);
FORCEPROP 1 LAST PART_NUMBER CH733LY8802
J 0
(-3225 2650);
DISPLAY 0.617021 (-3225 2650);
PAINT BLUE (-3225 2650);
DISPLAY INVISIBLE (-3225 2650);
FORCEPROP 1 LAST VOLTAGE 2.5V
J 0
(-3225 2800);
DISPLAY 0.617021 (-3225 2800);
PAINT SKYBLUE (-3225 2800);
FORCEPROP 1 LAST VALUE 330UF
J 0
(-3225 2900);
DISPLAY 0.617021 (-3225 2900);
PAINT SKYBLUE (-3225 2900);
FORCEPROP 1 LAST MATERIAL SPCAP
J 0
(-3225 2750);
DISPLAY 0.617021 (-3225 2750);
PAINT SKYBLUE (-3225 2750);
FORCEPROP 1 LAST PACK_TYPE SMLF
J 0
(-3225 2700);
DISPLAY 0.617021 (-3225 2700);
PAINT SKYBLUE (-3225 2700);
FORCEPROP 1 LAST TOLERANCE +10/-35%
J 0
(-3225 2850);
DISPLAY 0.617021 (-3225 2850);
PAINT SKYBLUE (-3225 2850);
FORCEPROP 1 LAST LOCATION PC418
J 0
(-3225 2950);
DISPLAY 0.617021 (-3225 2950);
PAINT AQUA (-3225 2950);
FORCEPROP 1 LASTPIN (-3275 2900) $PN 1
J 0
(-3265 2885);
DISPLAY 0.617021 (-3265 2885);
PAINT MONO (-3265 2885);
FORCEPROP 1 LASTPIN (-3275 2700) $PN 2
J 0
(-3265 2685);
DISPLAY 0.617021 (-3265 2685);
PAINT MONO (-3265 2685);
FORCEPROP 2 LAST CDS_LIB pure_quanta
J 0
(-3275 2800);
DISPLAY INVISIBLE (-3275 2800);
FORCEPROP 1 LAST PATH I70
J 0
(-3225 2950);
DISPLAY 0.978723 (-3225 2950);
DISPLAY INVISIBLE (-3225 2950);
FORCEPROP 1 LAST LOCATION PC418
J 0
(-3225 3000);
DISPLAY 1.021277 (-3225 3000);
PAINT AQUA (-3225 3000);
DISPLAY INVISIBLE (-3225 3000);
FORCEPROP 0 LAST $SEC 1
J 0
(-3225 3000);
DISPLAY 0.680851 (-3225 3000);
PAINT MONO (-3225 3000);
DISPLAY INVISIBLE (-3225 3000);
FORCEPROP 0 LAST CDS_SEC 1
J 0
(-3225 3000);
DISPLAY 1.021277 (-3225 3000);
DISPLAY INVISIBLE (-3225 3000);
FORCEADD UNIVERSAL_GND..1
(-2825 2450);
FORCEPROP 3 LASTPIN (-2825 2500) SIG_NAME GND\g
J 0
(-2815 2510);
DISPLAY 0.659574 (-2815 2510);
PAINT MONO (-2815 2510);
DISPLAY INVISIBLE (-2815 2510);
FORCEPROP 1 LAST HDL_POWER GND
J 1
(-2800 2375);
DISPLAY 0.872340 (-2800 2375);
PAINT GREEN (-2800 2375);
DISPLAY INVISIBLE (-2800 2375);
FORCEPROP 2 LAST CDS_LIB logical_power
J 0
(-2825 2450);
PAINT MONO (-2825 2450);
DISPLAY INVISIBLE (-2825 2450);
FORCEPROP 1 LAST PATH I71
J 0
(-2750 2450);
DISPLAY 0.872340 (-2750 2450);
PAINT AQUA (-2750 2450);
DISPLAY INVISIBLE (-2750 2450);
FORCEADD Q_CAPP..1
(-2825 2800);
FORCEPROP 1 LAST PART_NUMBER CH733LY8802
J 0
(-2750 2650);
DISPLAY 0.617021 (-2750 2650);
PAINT BLUE (-2750 2650);
DISPLAY INVISIBLE (-2750 2650);
FORCEPROP 1 LAST VOLTAGE 2.5V
J 0
(-2750 2800);
DISPLAY 0.617021 (-2750 2800);
PAINT SKYBLUE (-2750 2800);
FORCEPROP 1 LAST MATERIAL SPCAP
J 0
(-2750 2750);
DISPLAY 0.617021 (-2750 2750);
PAINT RED (-2750 2750);
FORCEPROP 1 LAST PACK_TYPE SMLF
J 0
(-2750 2700);
DISPLAY 0.617021 (-2750 2700);
PAINT SKYBLUE (-2750 2700);
FORCEPROP 1 LAST VALUE 330UF
J 0
(-2750 2900);
DISPLAY 0.617021 (-2750 2900);
PAINT SKYBLUE (-2750 2900);
FORCEPROP 1 LAST TOLERANCE +10/-35%
J 0
(-2750 2850);
DISPLAY 0.617021 (-2750 2850);
PAINT SKYBLUE (-2750 2850);
FORCEPROP 1 LAST LOCATION PC2172
J 0
(-2750 2950);
DISPLAY 0.617021 (-2750 2950);
PAINT AQUA (-2750 2950);
FORCEPROP 1 LASTPIN (-2825 2900) $PN 1
J 0
(-2815 2885);
DISPLAY 0.617021 (-2815 2885);
PAINT MONO (-2815 2885);
FORCEPROP 1 LASTPIN (-2825 2700) $PN 2
J 0
(-2815 2685);
DISPLAY 0.617021 (-2815 2685);
PAINT MONO (-2815 2685);
FORCEPROP 2 LAST CDS_LIB pure_quanta
J 0
(-2825 2800);
DISPLAY INVISIBLE (-2825 2800);
FORCEPROP 1 LAST PATH I72
J 0
(-2775 2950);
DISPLAY 0.978723 (-2775 2950);
DISPLAY INVISIBLE (-2775 2950);
FORCEPROP 2 LAST $SEC 1
J 0
(-2775 3000);
DISPLAY 0.680851 (-2775 3000);
PAINT MONO (-2775 3000);
DISPLAY INVISIBLE (-2775 3000);
FORCEPROP 2 LAST CDS_SEC 1
J 0
(-2775 3000);
DISPLAY 1.021277 (-2775 3000);
DISPLAY INVISIBLE (-2775 3000);
FORCEADD VCC15..1
(-2825 3125);
FORCEPROP 3 LASTPIN (-2825 3075) SIG_NAME PVCCFA_EHV_FIVRA_CPU1\g
J 0
(-2815 3085);
DISPLAY 0.659574 (-2815 3085);
PAINT MONO (-2815 3085);
DISPLAY INVISIBLE (-2815 3085);
FORCEPROP 1 LAST HDL_POWER PVCCFA_EHV_FIVRA_CPU1
J 1
(-2825 3175);
DISPLAY 0.617021 (-2825 3175);
PAINT GREEN (-2825 3175);
FORCEPROP 2 LAST CDS_LIB logical_power
J 0
(-2825 3125);
DISPLAY INVISIBLE (-2825 3125);
FORCEPROP 1 LAST PATH I73
J 0
(-2775 3150);
DISPLAY 0.872340 (-2775 3150);
PAINT AQUA (-2775 3150);
DISPLAY INVISIBLE (-2775 3150);
FORCEADD Q_CAP..1
(-4550 4475);
FORCEPROP 1 LAST PART_NUMBER CH622KMEA03
J 0
(-4500 4300);
DISPLAY 0.617021 (-4500 4300);
PAINT BLUE (-4500 4300);
DISPLAY INVISIBLE (-4500 4300);
FORCEPROP 1 LAST TOLERANCE 20%
J 0
(-4500 4450);
DISPLAY 0.617021 (-4500 4450);
PAINT SKYBLUE (-4500 4450);
FORCEPROP 1 LAST PACK_TYPE C0805
J 0
(-4500 4350);
DISPLAY 0.617021 (-4500 4350);
PAINT SKYBLUE (-4500 4350);
FORCEPROP 1 LAST VOLTAGE 4V
J 0
(-4500 4500);
DISPLAY 0.617021 (-4500 4500);
PAINT SKYBLUE (-4500 4500);
FORCEPROP 1 LAST VALUE 22UF
J 0
(-4500 4550);
DISPLAY 0.617021 (-4500 4550);
PAINT SKYBLUE (-4500 4550);
FORCEPROP 1 LAST MATERIAL X6S
J 0
(-4500 4400);
DISPLAY 0.617021 (-4500 4400);
PAINT SKYBLUE (-4500 4400);
FORCEPROP 1 LAST LOCATION PC410_P1_1
J 0
(-4500 4600);
DISPLAY 0.617021 (-4500 4600);
PAINT AQUA (-4500 4600);
FORCEPROP 1 LASTPIN (-4550 4575) $PN 1
J 0
(-4540 4555);
DISPLAY 0.617021 (-4540 4555);
PAINT MONO (-4540 4555);
FORCEPROP 1 LASTPIN (-4550 4375) $PN 2
J 0
(-4540 4355);
DISPLAY 0.617021 (-4540 4355);
PAINT MONO (-4540 4355);
FORCEPROP 2 LAST CDS_LIB pure_quanta
J 0
(-4550 4475);
DISPLAY INVISIBLE (-4550 4475);
FORCEPROP 1 LAST PATH I74
J 0
(-4500 4625);
DISPLAY 0.978723 (-4500 4625);
PAINT WHITE (-4500 4625);
DISPLAY INVISIBLE (-4500 4625);
FORCEPROP 1 LAST LOCATION PC410_P1_1
J 0
(-4500 4650);
DISPLAY 1.021277 (-4500 4650);
PAINT AQUA (-4500 4650);
DISPLAY INVISIBLE (-4500 4650);
FORCEPROP 0 LAST $SEC 1
J 0
(-4500 4650);
DISPLAY 0.680851 (-4500 4650);
PAINT MONO (-4500 4650);
DISPLAY INVISIBLE (-4500 4650);
FORCEPROP 0 LAST CDS_SEC 1
J 0
(-4500 4650);
DISPLAY 1.021277 (-4500 4650);
DISPLAY INVISIBLE (-4500 4650);
FORCEADD Q_CAP..1
(-4125 4475);
FORCEPROP 1 LAST PART_NUMBER CH622KMEA03
J 0
(-4075 4300);
DISPLAY 0.617021 (-4075 4300);
PAINT BLUE (-4075 4300);
DISPLAY INVISIBLE (-4075 4300);
FORCEPROP 1 LAST TOLERANCE 20%
J 0
(-4075 4450);
DISPLAY 0.617021 (-4075 4450);
PAINT SKYBLUE (-4075 4450);
FORCEPROP 1 LAST PACK_TYPE C0805
J 0
(-4075 4350);
DISPLAY 0.617021 (-4075 4350);
PAINT SKYBLUE (-4075 4350);
FORCEPROP 1 LAST VOLTAGE 4V
J 0
(-4075 4500);
DISPLAY 0.617021 (-4075 4500);
PAINT SKYBLUE (-4075 4500);
FORCEPROP 1 LAST MATERIAL X6S
J 0
(-4075 4400);
DISPLAY 0.617021 (-4075 4400);
PAINT SKYBLUE (-4075 4400);
FORCEPROP 1 LAST VALUE 22UF
J 0
(-4075 4550);
DISPLAY 0.617021 (-4075 4550);
PAINT SKYBLUE (-4075 4550);
FORCEPROP 1 LAST LOCATION PC412_P1_1
J 0
(-4075 4600);
DISPLAY 0.617021 (-4075 4600);
PAINT AQUA (-4075 4600);
FORCEPROP 1 LASTPIN (-4125 4575) $PN 1
J 0
(-4115 4555);
DISPLAY 0.617021 (-4115 4555);
PAINT MONO (-4115 4555);
FORCEPROP 1 LASTPIN (-4125 4375) $PN 2
J 0
(-4115 4355);
DISPLAY 0.617021 (-4115 4355);
PAINT MONO (-4115 4355);
FORCEPROP 2 LAST CDS_LIB pure_quanta
J 0
(-4125 4475);
DISPLAY INVISIBLE (-4125 4475);
FORCEPROP 1 LAST PATH I75
J 0
(-4075 4625);
DISPLAY 0.978723 (-4075 4625);
PAINT WHITE (-4075 4625);
DISPLAY INVISIBLE (-4075 4625);
FORCEPROP 1 LAST LOCATION PC412_P1_1
J 0
(-4075 4650);
DISPLAY 1.021277 (-4075 4650);
PAINT AQUA (-4075 4650);
DISPLAY INVISIBLE (-4075 4650);
FORCEPROP 0 LAST $SEC 1
J 0
(-4075 4650);
DISPLAY 0.680851 (-4075 4650);
PAINT MONO (-4075 4650);
DISPLAY INVISIBLE (-4075 4650);
FORCEPROP 0 LAST CDS_SEC 1
J 0
(-4075 4650);
DISPLAY 1.021277 (-4075 4650);
DISPLAY INVISIBLE (-4075 4650);
FORCEADD GND..1
(-5000 5100);
FORCEPROP 3 LASTPIN (-5000 5150) SIG_NAME GND\g
J 0
(-4990 5160);
DISPLAY 0.659574 (-4990 5160);
PAINT MONO (-4990 5160);
DISPLAY INVISIBLE (-4990 5160);
FORCEPROP 1 LAST HDL_POWER GND
J 0
(-5000 5250);
DISPLAY 0.872340 (-5000 5250);
PAINT GREEN (-5000 5250);
DISPLAY INVISIBLE (-5000 5250);
FORCEPROP 2 LAST CDS_LIB logical_power
J 0
(-5000 5100);
DISPLAY INVISIBLE (-5000 5100);
FORCEPROP 1 LAST SIZE 1B
J 0
(-4925 5050);
DISPLAY 0.872340 (-4925 5050);
PAINT AQUA (-4925 5050);
DISPLAY INVISIBLE (-4925 5050);
FORCEPROP 1 LAST PATH I76
J 0
(-4925 5100);
DISPLAY 0.872340 (-4925 5100);
PAINT AQUA (-4925 5100);
DISPLAY INVISIBLE (-4925 5100);
FORCEADD Q_CAP..1
(-5000 5350);
FORCEPROP 1 LAST PART_NUMBER CH4106K1B01
J 0
(-4950 5200);
DISPLAY 0.787234 (-4950 5200);
DISPLAY INVISIBLE (-4950 5200);
FORCEPROP 1 LAST PACK_TYPE C0402
J 0
(-4950 5150);
DISPLAY 0.787234 (-4950 5150);
FORCEPROP 1 LAST VOLTAGE 50V
J 0
(-4950 5350);
DISPLAY 0.787234 (-4950 5350);
FORCEPROP 1 LAST VALUE 100NF
J 0
(-4950 5400);
DISPLAY 0.787234 (-4950 5400);
FORCEPROP 1 LAST TOLERANCE 10%
J 0
(-4950 5300);
DISPLAY 0.787234 (-4950 5300);
FORCEPROP 1 LAST MATERIAL X7R
J 0
(-4950 5250);
DISPLAY 0.787234 (-4950 5250);
FORCEPROP 1 LAST LOCATION PC1657
J 0
(-4950 5450);
DISPLAY 0.787234 (-4950 5450);
FORCEPROP 1 LASTPIN (-5000 5450) $PN 1
J 0
(-4990 5430);
DISPLAY 0.787234 (-4990 5430);
PAINT MONO (-4990 5430);
FORCEPROP 1 LASTPIN (-5000 5250) $PN 2
J 0
(-4990 5230);
DISPLAY 0.787234 (-4990 5230);
PAINT MONO (-4990 5230);
FORCEPROP 2 LAST CDS_LIB pure_quanta
J 0
(-5000 5350);
DISPLAY INVISIBLE (-5000 5350);
FORCEPROP 1 LAST PATH I77
J 0
(-4950 5500);
DISPLAY 0.978723 (-4950 5500);
PAINT WHITE (-4950 5500);
DISPLAY INVISIBLE (-4950 5500);
FORCEPROP 0 LAST $SEC 1
J 0
(-4950 5500);
DISPLAY 0.680851 (-4950 5500);
PAINT MONO (-4950 5500);
DISPLAY INVISIBLE (-4950 5500);
FORCEPROP 0 LAST CDS_SEC 1
J 0
(-4950 5500);
DISPLAY 1.021277 (-4950 5500);
DISPLAY INVISIBLE (-4950 5500);
FORCEADD VCC15..1
(-5000 5725);
FORCEPROP 3 LASTPIN (-5000 5675) SIG_NAME P12V_AUX\g
J 0
(-4990 5685);
DISPLAY 0.659574 (-4990 5685);
PAINT MONO (-4990 5685);
DISPLAY INVISIBLE (-4990 5685);
FORCEPROP 1 LAST HDL_POWER P12V_AUX
J 1
(-5000 5775);
DISPLAY 0.617021 (-5000 5775);
PAINT GREEN (-5000 5775);
FORCEPROP 2 LAST CDS_LIB logical_power
J 0
(-5000 5725);
DISPLAY INVISIBLE (-5000 5725);
FORCEPROP 1 LAST PATH I78
J 0
(-4950 5750);
DISPLAY 0.872340 (-4950 5750);
PAINT AQUA (-4950 5750);
DISPLAY INVISIBLE (-4950 5750);
FORCEADD Q_INDUCTOR..1
(-4575 5575);
FORCEPROP 1 LAST PART_NUMBER CV+10G0MZ04
J 0
(-4675 5325);
DISPLAY 0.617021 (-4675 5325);
PAINT BLUE (-4675 5325);
DISPLAY INVISIBLE (-4675 5325);
FORCEPROP 2 LAST VALUE 100NH/16A
J 0
(-4675 5475);
DISPLAY 0.617021 (-4675 5475);
PAINT SKYBLUE (-4675 5475);
FORCEPROP 1 LAST MATERIAL IND
J 0
(-4675 5375);
DISPLAY 0.617021 (-4675 5375);
PAINT SKYBLUE (-4675 5375);
FORCEPROP 2 LAST PACK_TYPE SMLF
J 0
(-4675 5425);
DISPLAY 0.617021 (-4675 5425);
PAINT SKYBLUE (-4675 5425);
FORCEPROP 1 LAST LOCATION PL43
J 0
(-4850 5560);
DISPLAY 0.617021 (-4850 5560);
PAINT AQUA (-4850 5560);
FORCEPROP 2 LASTPIN (-4675 5550) $PN 1
J 2
(-4685 5560);
DISPLAY 0.617021 (-4685 5560);
FORCEPROP 2 LASTPIN (-4475 5550) $PN 2
J 0
(-4465 5560);
DISPLAY 0.617021 (-4465 5560);
FORCEPROP 2 LAST CDS_LIB pure_quanta
J 0
(-4575 5575);
PAINT MONO (-4575 5575);
DISPLAY INVISIBLE (-4575 5575);
FORCEPROP 1 LAST NEEDS_NO_SIZE TRUE
J 0
(-4575 5575);
DISPLAY 0.468085 (-4575 5575);
PAINT GREEN (-4575 5575);
DISPLAY INVISIBLE (-4575 5575);
FORCEPROP 1 LAST PATH I79
J 0
(-4500 5630);
DISPLAY 0.723404 (-4500 5630);
PAINT GREEN (-4500 5630);
DISPLAY INVISIBLE (-4500 5630);
FORCEPROP 2 LAST $SEC 1
J 0
(-4500 5675);
DISPLAY 0.680851 (-4500 5675);
PAINT MONO (-4500 5675);
DISPLAY INVISIBLE (-4500 5675);
FORCEPROP 2 LAST CDS_SEC 1
J 0
(-4500 5675);
DISPLAY 1.021277 (-4500 5675);
DISPLAY INVISIBLE (-4500 5675);
FORCEADD Q_CAP..2
(-9975 1675);
FORCEPROP 1 LAST PART_NUMBER CH4104K1B00
J 1
(-9750 1725);
DISPLAY 0.617021 (-9750 1725);
PAINT BLUE (-9750 1725);
DISPLAY INVISIBLE (-9750 1725);
FORCEPROP 1 LAST MATERIAL X7R
J 0
(-9575 1725);
DISPLAY 0.617021 (-9575 1725);
PAINT SKYBLUE (-9575 1725);
FORCEPROP 1 LAST PACK_TYPE 0402
J 1
(-9550 1675);
DISPLAY 0.617021 (-9550 1675);
PAINT SKYBLUE (-9550 1675);
FORCEPROP 1 LAST TOLERANCE 10%
J 2
(-9375 1725);
DISPLAY 0.617021 (-9375 1725);
PAINT SKYBLUE (-9375 1725);
FORCEPROP 1 LAST VOLTAGE 25V
J 0
(-9725 1675);
DISPLAY 0.617021 (-9725 1675);
PAINT SKYBLUE (-9725 1675);
FORCEPROP 1 LAST VALUE 0.1UF
J 2
(-9750 1675);
DISPLAY 0.617021 (-9750 1675);
PAINT SKYBLUE (-9750 1675);
FORCEPROP 1 LAST LOCATION PC1368
J 1
(-10175 1675);
DISPLAY 0.617021 (-10175 1675);
PAINT AQUA (-10175 1675);
FORCEPROP 1 LASTPIN (-10075 1675) $PN 1
J 0
(-10085 1690);
DISPLAY 0.617021 (-10085 1690);
FORCEPROP 1 LASTPIN (-9875 1675) $PN 2
J 0
(-9890 1690);
DISPLAY 0.617021 (-9890 1690);
FORCEPROP 2 LAST CDS_LIB pure_quanta
J 0
(-9975 1675);
PAINT MONO (-9975 1675);
DISPLAY INVISIBLE (-9975 1675);
FORCEPROP 1 LAST PATH I8
J 0
(-9975 1875);
DISPLAY 0.978723 (-9975 1875);
PAINT WHITE (-9975 1875);
DISPLAY INVISIBLE (-9975 1875);
FORCEPROP 2 LAST $SEC 1
J 0
(-9975 1925);
DISPLAY 0.680851 (-9975 1925);
PAINT MONO (-9975 1925);
DISPLAY INVISIBLE (-9975 1925);
FORCEPROP 2 LAST CDS_SEC 1
J 0
(-9975 1925);
DISPLAY 1.021277 (-9975 1925);
DISPLAY INVISIBLE (-9975 1925);
FORCEADD Q_CAP..1
(-4250 5325);
FORCEPROP 1 LAST PART_NUMBER CH6223MEA01
J 0
(-4200 5200);
DISPLAY 0.404255 (-4200 5200);
DISPLAY INVISIBLE (-4200 5200);
FORCEPROP 1 LAST TOLERANCE 20%
J 0
(-4200 5300);
DISPLAY 0.510638 (-4200 5300);
FORCEPROP 1 LAST VALUE 22UF
J 0
(-4200 5400);
DISPLAY 0.510638 (-4200 5400);
FORCEPROP 1 LAST VOLTAGE 16V
J 0
(-4200 5350);
DISPLAY 0.510638 (-4200 5350);
FORCEPROP 1 LAST MATERIAL X6S
J 0
(-4200 5250);
DISPLAY 0.510638 (-4200 5250);
FORCEPROP 1 LAST PACK_TYPE C0805
J 0
(-4200 5150);
DISPLAY 0.510638 (-4200 5150);
FORCEPROP 1 LAST LOCATION PC1677
J 0
(-4200 5450);
DISPLAY 0.510638 (-4200 5450);
FORCEPROP 1 LASTPIN (-4250 5425) $PN 1
J 0
(-4240 5405);
DISPLAY 0.787234 (-4240 5405);
PAINT MONO (-4240 5405);
FORCEPROP 1 LASTPIN (-4250 5225) $PN 2
J 0
(-4240 5205);
DISPLAY 0.787234 (-4240 5205);
PAINT MONO (-4240 5205);
FORCEPROP 2 LAST CDS_LIB pure_quanta
J 0
(-4250 5325);
DISPLAY INVISIBLE (-4250 5325);
FORCEPROP 1 LAST PATH I80
J 0
(-4200 5475);
DISPLAY 0.978723 (-4200 5475);
PAINT WHITE (-4200 5475);
DISPLAY INVISIBLE (-4200 5475);
FORCEPROP 0 LAST $SEC 1
J 0
(-4200 5475);
DISPLAY 0.680851 (-4200 5475);
PAINT MONO (-4200 5475);
DISPLAY INVISIBLE (-4200 5475);
FORCEPROP 0 LAST CDS_SEC 1
J 0
(-4200 5475);
DISPLAY 1.021277 (-4200 5475);
DISPLAY INVISIBLE (-4200 5475);
FORCEADD UNIVERSAL_GND..1
(-3825 4100);
FORCEPROP 3 LASTPIN (-3825 4150) SIG_NAME GND\g
J 0
(-3815 4160);
DISPLAY 0.659574 (-3815 4160);
PAINT MONO (-3815 4160);
DISPLAY INVISIBLE (-3815 4160);
FORCEPROP 1 LAST HDL_POWER GND
J 1
(-3800 4025);
DISPLAY 0.872340 (-3800 4025);
PAINT GREEN (-3800 4025);
DISPLAY INVISIBLE (-3800 4025);
FORCEPROP 2 LAST CDS_LIB logical_power
J 0
(-3825 4100);
PAINT MONO (-3825 4100);
DISPLAY INVISIBLE (-3825 4100);
FORCEPROP 1 LAST PATH I81
J 0
(-3750 4100);
DISPLAY 0.872340 (-3750 4100);
PAINT AQUA (-3750 4100);
DISPLAY INVISIBLE (-3750 4100);
FORCEADD VCC15..1
(-3825 4875);
FORCEPROP 3 LASTPIN (-3825 4825) SIG_NAME PVCCFA_EHV_FIVRA_CPU1\g
J 0
(-3815 4835);
DISPLAY 0.659574 (-3815 4835);
PAINT MONO (-3815 4835);
DISPLAY INVISIBLE (-3815 4835);
FORCEPROP 1 LAST HDL_POWER PVCCFA_EHV_FIVRA_CPU1
J 1
(-3825 4925);
DISPLAY 0.617021 (-3825 4925);
PAINT GREEN (-3825 4925);
FORCEPROP 2 LAST CDS_LIB logical_power
J 0
(-3825 4875);
DISPLAY INVISIBLE (-3825 4875);
FORCEPROP 1 LAST PATH I82
J 0
(-3775 4900);
DISPLAY 0.872340 (-3775 4900);
PAINT AQUA (-3775 4900);
DISPLAY INVISIBLE (-3775 4900);
FORCEADD Q_CAP..1
(-3950 5325);
FORCEPROP 1 LAST PART_NUMBER CH6223MEA01
J 0
(-3900 5200);
DISPLAY 0.404255 (-3900 5200);
DISPLAY INVISIBLE (-3900 5200);
FORCEPROP 1 LAST TOLERANCE 20%
J 0
(-3900 5300);
DISPLAY 0.510638 (-3900 5300);
FORCEPROP 1 LAST MATERIAL X6S
J 0
(-3900 5250);
DISPLAY 0.510638 (-3900 5250);
FORCEPROP 1 LAST PACK_TYPE C0805
J 0
(-3900 5150);
DISPLAY 0.510638 (-3900 5150);
FORCEPROP 1 LAST VALUE 22UF
J 0
(-3900 5400);
DISPLAY 0.510638 (-3900 5400);
FORCEPROP 1 LAST VOLTAGE 16V
J 0
(-3900 5350);
DISPLAY 0.510638 (-3900 5350);
FORCEPROP 1 LAST LOCATION PC1678
J 0
(-3900 5450);
DISPLAY 0.510638 (-3900 5450);
FORCEPROP 1 LASTPIN (-3950 5425) $PN 1
J 0
(-3940 5405);
DISPLAY 0.787234 (-3940 5405);
PAINT MONO (-3940 5405);
FORCEPROP 1 LASTPIN (-3950 5225) $PN 2
J 0
(-3940 5205);
DISPLAY 0.787234 (-3940 5205);
PAINT MONO (-3940 5205);
FORCEPROP 2 LAST CDS_LIB pure_quanta
J 0
(-3950 5325);
DISPLAY INVISIBLE (-3950 5325);
FORCEPROP 1 LAST PATH I83
J 0
(-3900 5475);
DISPLAY 0.978723 (-3900 5475);
PAINT WHITE (-3900 5475);
DISPLAY INVISIBLE (-3900 5475);
FORCEPROP 0 LAST $SEC 1
J 0
(-3900 5475);
DISPLAY 0.680851 (-3900 5475);
PAINT MONO (-3900 5475);
DISPLAY INVISIBLE (-3900 5475);
FORCEPROP 0 LAST CDS_SEC 1
J 0
(-3900 5475);
DISPLAY 1.021277 (-3900 5475);
DISPLAY INVISIBLE (-3900 5475);
FORCEADD Q_CAP..1
(-3675 5325);
FORCEPROP 1 LAST PART_NUMBER CH6223MEA01
J 0
(-3625 5200);
DISPLAY 0.404255 (-3625 5200);
DISPLAY INVISIBLE (-3625 5200);
FORCEPROP 1 LAST TOLERANCE 20%
J 0
(-3625 5300);
DISPLAY 0.510638 (-3625 5300);
FORCEPROP 1 LAST PACK_TYPE C0805
J 0
(-3625 5150);
DISPLAY 0.510638 (-3625 5150);
FORCEPROP 1 LAST MATERIAL X6S
J 0
(-3625 5250);
DISPLAY 0.510638 (-3625 5250);
FORCEPROP 1 LAST VOLTAGE 16V
J 0
(-3625 5350);
DISPLAY 0.510638 (-3625 5350);
FORCEPROP 1 LAST VALUE 22UF
J 0
(-3625 5400);
DISPLAY 0.510638 (-3625 5400);
FORCEPROP 1 LAST LOCATION PC1679
J 0
(-3625 5450);
DISPLAY 0.510638 (-3625 5450);
FORCEPROP 1 LASTPIN (-3675 5425) $PN 1
J 0
(-3665 5405);
DISPLAY 0.787234 (-3665 5405);
PAINT MONO (-3665 5405);
FORCEPROP 1 LASTPIN (-3675 5225) $PN 2
J 0
(-3665 5205);
DISPLAY 0.787234 (-3665 5205);
PAINT MONO (-3665 5205);
FORCEPROP 2 LAST CDS_LIB pure_quanta
J 0
(-3675 5325);
DISPLAY INVISIBLE (-3675 5325);
FORCEPROP 1 LAST PATH I84
J 0
(-3625 5475);
DISPLAY 0.978723 (-3625 5475);
PAINT WHITE (-3625 5475);
DISPLAY INVISIBLE (-3625 5475);
FORCEPROP 0 LAST $SEC 1
J 0
(-3625 5475);
DISPLAY 0.680851 (-3625 5475);
PAINT MONO (-3625 5475);
DISPLAY INVISIBLE (-3625 5475);
FORCEPROP 0 LAST CDS_SEC 1
J 0
(-3625 5475);
DISPLAY 1.021277 (-3625 5475);
DISPLAY INVISIBLE (-3625 5475);
FORCEADD Q_CAP..1
(-3400 5325);
FORCEPROP 1 LAST PART_NUMBER CH6223MEA01
J 0
(-3350 5200);
DISPLAY 0.404255 (-3350 5200);
DISPLAY INVISIBLE (-3350 5200);
FORCEPROP 1 LAST TOLERANCE 20%
J 0
(-3350 5300);
DISPLAY 0.510638 (-3350 5300);
FORCEPROP 1 LAST VOLTAGE 16V
J 0
(-3350 5350);
DISPLAY 0.510638 (-3350 5350);
FORCEPROP 1 LAST VALUE 22UF
J 0
(-3350 5400);
DISPLAY 0.510638 (-3350 5400);
FORCEPROP 1 LAST MATERIAL X6S
J 0
(-3350 5250);
DISPLAY 0.510638 (-3350 5250);
FORCEPROP 1 LAST PACK_TYPE C0805
J 0
(-3350 5150);
DISPLAY 0.510638 (-3350 5150);
FORCEPROP 1 LAST LOCATION PC1680
J 0
(-3350 5450);
DISPLAY 0.510638 (-3350 5450);
FORCEPROP 1 LASTPIN (-3400 5425) $PN 1
J 0
(-3390 5405);
DISPLAY 0.787234 (-3390 5405);
PAINT MONO (-3390 5405);
FORCEPROP 1 LASTPIN (-3400 5225) $PN 2
J 0
(-3390 5205);
DISPLAY 0.787234 (-3390 5205);
PAINT MONO (-3390 5205);
FORCEPROP 2 LAST CDS_LIB pure_quanta
J 0
(-3400 5325);
DISPLAY INVISIBLE (-3400 5325);
FORCEPROP 1 LAST PATH I85
J 0
(-3350 5475);
DISPLAY 0.978723 (-3350 5475);
PAINT WHITE (-3350 5475);
DISPLAY INVISIBLE (-3350 5475);
FORCEPROP 0 LAST $SEC 1
J 0
(-3350 5475);
DISPLAY 0.680851 (-3350 5475);
PAINT MONO (-3350 5475);
DISPLAY INVISIBLE (-3350 5475);
FORCEPROP 0 LAST CDS_SEC 1
J 0
(-3350 5475);
DISPLAY 1.021277 (-3350 5475);
DISPLAY INVISIBLE (-3350 5475);
FORCEADD UNIVERSAL_GND..1
(-3125 5025);
FORCEPROP 3 LASTPIN (-3125 5075) SIG_NAME GND\g
J 0
(-3115 5085);
DISPLAY 0.659574 (-3115 5085);
PAINT MONO (-3115 5085);
DISPLAY INVISIBLE (-3115 5085);
FORCEPROP 1 LAST HDL_POWER GND
J 1
(-3100 4950);
DISPLAY 0.872340 (-3100 4950);
PAINT GREEN (-3100 4950);
DISPLAY INVISIBLE (-3100 4950);
FORCEPROP 2 LAST CDS_LIB logical_power
J 0
(-3125 5025);
PAINT MONO (-3125 5025);
DISPLAY INVISIBLE (-3125 5025);
FORCEPROP 1 LAST PATH I86
J 0
(-3050 5025);
DISPLAY 0.872340 (-3050 5025);
PAINT AQUA (-3050 5025);
DISPLAY INVISIBLE (-3050 5025);
FORCEADD Q_CAPP..1
(-3125 5325);
FORCEPROP 1 LAST PART_NUMBER CC72703MD38
J 0
(-3075 5150);
DISPLAY 0.617021 (-3075 5150);
PAINT BLUE (-3075 5150);
DISPLAY INVISIBLE (-3075 5150);
FORCEPROP 1 LAST PACK_TYPE THLF
J 0
(-3075 5200);
DISPLAY 0.617021 (-3075 5200);
PAINT SKYBLUE (-3075 5200);
FORCEPROP 1 LAST TOLERANCE 20%
J 0
(-3075 5350);
DISPLAY 0.617021 (-3075 5350);
PAINT SKYBLUE (-3075 5350);
FORCEPROP 1 LAST MATERIAL OSCON
J 0
(-3075 5250);
DISPLAY 0.617021 (-3075 5250);
PAINT SKYBLUE (-3075 5250);
FORCEPROP 1 LAST VALUE 270UF
J 0
(-3075 5400);
DISPLAY 0.617021 (-3075 5400);
PAINT SKYBLUE (-3075 5400);
FORCEPROP 1 LAST VOLTAGE 16V
J 0
(-3075 5300);
DISPLAY 0.617021 (-3075 5300);
PAINT SKYBLUE (-3075 5300);
FORCEPROP 1 LAST LOCATION PC417
J 0
(-3075 5450);
DISPLAY 0.617021 (-3075 5450);
PAINT AQUA (-3075 5450);
FORCEPROP 1 LASTPIN (-3125 5425) $PN 1
J 0
(-3115 5410);
DISPLAY 0.617021 (-3115 5410);
PAINT MONO (-3115 5410);
FORCEPROP 1 LASTPIN (-3125 5225) $PN 2
J 0
(-3115 5210);
DISPLAY 0.617021 (-3115 5210);
PAINT MONO (-3115 5210);
FORCEPROP 2 LAST CDS_LIB pure_quanta
J 0
(-3125 5325);
DISPLAY INVISIBLE (-3125 5325);
FORCEPROP 1 LAST PATH I87
J 0
(-3075 5475);
DISPLAY 0.978723 (-3075 5475);
DISPLAY INVISIBLE (-3075 5475);
FORCEPROP 1 LAST LOCATION PC417
J 0
(-3075 5500);
DISPLAY 1.021277 (-3075 5500);
PAINT AQUA (-3075 5500);
DISPLAY INVISIBLE (-3075 5500);
FORCEPROP 0 LAST $SEC 1
J 0
(-3075 5500);
DISPLAY 0.680851 (-3075 5500);
PAINT MONO (-3075 5500);
DISPLAY INVISIBLE (-3075 5500);
FORCEPROP 0 LAST CDS_SEC 1
J 0
(-3075 5500);
DISPLAY 1.021277 (-3075 5500);
DISPLAY INVISIBLE (-3075 5500);
FORCEADD VCC15..1
(-2975 5700);
FORCEPROP 3 LASTPIN (-2975 5650) SIG_NAME SW_P12V_PVCCFA_EHV_FIVRA_CPU1_L\g
J 0
(-2965 5660);
DISPLAY 0.659574 (-2965 5660);
PAINT MONO (-2965 5660);
DISPLAY INVISIBLE (-2965 5660);
FORCEPROP 1 LAST HDL_POWER SW_P12V_PVCCFA_EHV_FIVRA_CPU1_L
J 1
(-2925 5750);
DISPLAY 0.617021 (-2925 5750);
PAINT GREEN (-2925 5750);
FORCEPROP 2 LAST CDS_LIB logical_power
J 0
(-2975 5700);
DISPLAY INVISIBLE (-2975 5700);
FORCEPROP 1 LAST PATH I88
J 0
(-2925 5725);
DISPLAY 0.872340 (-2925 5725);
PAINT AQUA (-2925 5725);
DISPLAY INVISIBLE (-2925 5725);
FORCEADD ISL99390FRZTR5935..1
(-8725 4675);
FORCEPROP 1 LAST PART_NUMBER AL099390004
J 0
(-9025 5475);
DISPLAY 0.617021 (-9025 5475);
PAINT BLUE (-9025 5475);
DISPLAY INVISIBLE (-9025 5475);
FORCEPROP 2 LAST PART_TYPE SMLF
J 0
(-9025 5575);
DISPLAY 0.808511 (-9025 5575);
FORCEPROP 2 LAST VALUE ISL99390FRZ-TR5935
J 0
(-9000 5425);
DISPLAY 0.617021 (-9000 5425);
PAINT SKYBLUE (-9000 5425);
FORCEPROP 1 LAST MATERIAL IC
J 0
(-9025 5400);
DISPLAY 0.617021 (-9025 5400);
PAINT SKYBLUE (-9025 5400);
FORCEPROP 1 LAST LOCATION PU75_P1_1
J 0
(-9025 5525);
DISPLAY 0.617021 (-9025 5525);
PAINT AQUA (-9025 5525);
FORCEPROP 2 LASTPIN (-8325 4225) $PN 2
J 0
(-8315 4235);
DISPLAY 0.617021 (-8315 4235);
PAINT MONO (-8315 4235);
FORCEPROP 2 LASTPIN (-8325 5025) $PN 33
J 0
(-8315 5035);
DISPLAY 0.617021 (-8315 5035);
PAINT MONO (-8315 5035);
FORCEPROP 2 LASTPIN (-9175 4425) $PN 31
J 2
(-9185 4435);
DISPLAY 0.617021 (-9185 4435);
PAINT MONO (-9185 4435);
FORCEPROP 2 LASTPIN (-9175 4825) $PN 35
J 2
(-9185 4835);
DISPLAY 0.617021 (-9185 4835);
PAINT MONO (-9185 4835);
FORCEPROP 2 LASTPIN (-8325 4375) $PN 6
J 0
(-8315 4385);
DISPLAY 0.617021 (-8315 4385);
PAINT MONO (-8315 4385);
FORCEPROP 2 LASTPIN (-8325 4325) $PN 41
J 0
(-8315 4335);
DISPLAY 0.617021 (-8315 4335);
PAINT MONO (-8315 4335);
FORCEPROP 2 LASTPIN (-9175 4675) $PN 38
J 2
(-9185 4685);
DISPLAY 0.617021 (-9185 4685);
PAINT MONO (-9185 4685);
FORCEPROP 2 LASTPIN (-9175 4375) $PN 37
J 2
(-9185 4385);
DISPLAY 0.617021 (-9185 4385);
PAINT MONO (-9185 4385);
FORCEPROP 2 LASTPIN (-8325 4175) $PN 5
J 0
(-8315 4185);
DISPLAY 0.617021 (-8315 4185);
PAINT MONO (-8315 4185);
FORCEPROP 2 LASTPIN (-8325 4125) $PN 7_9-20_24
J 0
(-8315 4135);
DISPLAY 0.617021 (-8315 4135);
PAINT MONO (-8315 4135);
FORCEPROP 2 LASTPIN (-8325 4075) $PN 40
J 0
(-8315 4085);
DISPLAY 0.617021 (-8315 4085);
PAINT MONO (-8315 4085);
FORCEPROP 2 LASTPIN (-8325 4775) $PN 32
J 0
(-8315 4785);
DISPLAY 0.617021 (-8315 4785);
PAINT MONO (-8315 4785);
FORCEPROP 2 LASTPIN (-9175 5325) $PN 4
J 2
(-9185 5335);
DISPLAY 0.617021 (-9185 5335);
PAINT MONO (-9185 5335);
FORCEPROP 2 LASTPIN (-9175 4075) $PN 34
J 2
(-9185 4085);
DISPLAY 0.617021 (-9185 4085);
PAINT MONO (-9185 4085);
FORCEPROP 2 LASTPIN (-9175 4575) $PN 39
J 2
(-9185 4585);
DISPLAY 0.617021 (-9185 4585);
PAINT MONO (-9185 4585);
FORCEPROP 2 LASTPIN (-8325 4675) $PN 10_19
J 0
(-8315 4685);
DISPLAY 0.617021 (-8315 4685);
PAINT MONO (-8315 4685);
FORCEPROP 2 LASTPIN (-9175 4175) $PN 36
J 2
(-9185 4185);
DISPLAY 0.617021 (-9185 4185);
PAINT MONO (-9185 4185);
FORCEPROP 2 LASTPIN (-9175 5025) $PN 3
J 2
(-9185 5035);
DISPLAY 0.617021 (-9185 5035);
PAINT MONO (-9185 5035);
FORCEPROP 2 LASTPIN (-8325 5325) $PN 25_29
J 0
(-8315 5335);
DISPLAY 0.617021 (-8315 5335);
PAINT MONO (-8315 5335);
FORCEPROP 2 LASTPIN (-8325 5275) $PN 30
J 0
(-8315 5285);
DISPLAY 0.617021 (-8315 5285);
PAINT MONO (-8315 5285);
FORCEPROP 2 LASTPIN (-8325 4425) $PN 1
J 0
(-8315 4435);
DISPLAY 0.617021 (-8315 4435);
PAINT MONO (-8315 4435);
FORCEPROP 2 LAST CDS_LIB pure_quanta
J 0
(-8725 4675);
DISPLAY INVISIBLE (-8725 4675);
FORCEPROP 1 LAST CDS_LMAN_SYM_OUTLINE -300,700,250,-650
J 0
(-8725 4675);
DISPLAY 0.468085 (-8725 4675);
PAINT GREEN (-8725 4675);
DISPLAY INVISIBLE (-8725 4675);
FORCEPROP 1 LAST NEEDS_NO_SIZE TRUE
J 0
(-8725 4675);
DISPLAY 0.723404 (-8725 4675);
PAINT GREEN (-8725 4675);
DISPLAY INVISIBLE (-8725 4675);
FORCEPROP 1 LAST PATH I89
J 0
(-8725 4675);
DISPLAY 0.723404 (-8725 4675);
PAINT GREEN (-8725 4675);
DISPLAY INVISIBLE (-8725 4675);
FORCEPROP 2 LAST $SEC 1
J 0
(-9025 5600);
DISPLAY 0.680851 (-9025 5600);
PAINT MONO (-9025 5600);
DISPLAY INVISIBLE (-9025 5600);
FORCEPROP 2 LAST CDS_SEC 1
J 0
(-8975 5675);
DISPLAY 1.021277 (-8975 5675);
DISPLAY INVISIBLE (-8975 5675);
FORCEADD ISL99390FRZTR5935..1
(-8725 1875);
FORCEPROP 1 LAST PART_NUMBER AL099390004
J 0
(-9025 2675);
DISPLAY 0.617021 (-9025 2675);
PAINT BLUE (-9025 2675);
DISPLAY INVISIBLE (-9025 2675);
FORCEPROP 1 LAST MATERIAL IC
J 0
(-9025 2600);
DISPLAY 0.617021 (-9025 2600);
PAINT SKYBLUE (-9025 2600);
FORCEPROP 2 LAST PART_TYPE SMLF
J 0
(-9025 2925);
DISPLAY 0.808511 (-9025 2925);
FORCEPROP 2 LAST VALUE ISL99390FRZ-TR5935
J 0
(-9025 2850);
DISPLAY 0.617021 (-9025 2850);
PAINT SKYBLUE (-9025 2850);
FORCEPROP 1 LAST LOCATION PU76_P1_2
J 0
(-9025 2750);
DISPLAY 0.617021 (-9025 2750);
PAINT AQUA (-9025 2750);
FORCEPROP 2 LASTPIN (-8325 1425) $PN 2
J 0
(-8315 1435);
DISPLAY 0.617021 (-8315 1435);
PAINT MONO (-8315 1435);
FORCEPROP 2 LASTPIN (-8325 2225) $PN 33
J 0
(-8315 2235);
DISPLAY 0.617021 (-8315 2235);
PAINT MONO (-8315 2235);
FORCEPROP 2 LASTPIN (-9175 1625) $PN 31
J 2
(-9185 1635);
DISPLAY 0.617021 (-9185 1635);
PAINT MONO (-9185 1635);
FORCEPROP 2 LASTPIN (-9175 2025) $PN 35
J 2
(-9185 2035);
DISPLAY 0.617021 (-9185 2035);
PAINT MONO (-9185 2035);
FORCEPROP 2 LASTPIN (-8325 1575) $PN 6
J 0
(-8315 1585);
DISPLAY 0.617021 (-8315 1585);
PAINT MONO (-8315 1585);
FORCEPROP 2 LASTPIN (-8325 1525) $PN 41
J 0
(-8315 1535);
DISPLAY 0.617021 (-8315 1535);
PAINT MONO (-8315 1535);
FORCEPROP 2 LASTPIN (-9175 1875) $PN 38
J 2
(-9185 1885);
DISPLAY 0.617021 (-9185 1885);
PAINT MONO (-9185 1885);
FORCEPROP 2 LASTPIN (-9175 1575) $PN 37
J 2
(-9185 1585);
DISPLAY 0.617021 (-9185 1585);
PAINT MONO (-9185 1585);
FORCEPROP 2 LASTPIN (-8325 1375) $PN 5
J 0
(-8315 1385);
DISPLAY 0.617021 (-8315 1385);
PAINT MONO (-8315 1385);
FORCEPROP 2 LASTPIN (-8325 1325) $PN 7_9-20_24
J 0
(-8315 1335);
DISPLAY 0.617021 (-8315 1335);
PAINT MONO (-8315 1335);
FORCEPROP 2 LASTPIN (-8325 1275) $PN 40
J 0
(-8315 1285);
DISPLAY 0.617021 (-8315 1285);
PAINT MONO (-8315 1285);
FORCEPROP 2 LASTPIN (-8325 1975) $PN 32
J 0
(-8315 1985);
DISPLAY 0.617021 (-8315 1985);
PAINT MONO (-8315 1985);
FORCEPROP 2 LASTPIN (-9175 2525) $PN 4
J 2
(-9185 2535);
DISPLAY 0.617021 (-9185 2535);
PAINT MONO (-9185 2535);
FORCEPROP 2 LASTPIN (-9175 1275) $PN 34
J 2
(-9185 1285);
DISPLAY 0.617021 (-9185 1285);
PAINT MONO (-9185 1285);
FORCEPROP 2 LASTPIN (-9175 1775) $PN 39
J 2
(-9185 1785);
DISPLAY 0.617021 (-9185 1785);
PAINT MONO (-9185 1785);
FORCEPROP 2 LASTPIN (-8325 1875) $PN 10_19
J 0
(-8315 1885);
DISPLAY 0.617021 (-8315 1885);
PAINT MONO (-8315 1885);
FORCEPROP 2 LASTPIN (-9175 1375) $PN 36
J 2
(-9185 1385);
DISPLAY 0.617021 (-9185 1385);
PAINT MONO (-9185 1385);
FORCEPROP 2 LASTPIN (-9175 2225) $PN 3
J 2
(-9185 2235);
DISPLAY 0.617021 (-9185 2235);
PAINT MONO (-9185 2235);
FORCEPROP 2 LASTPIN (-8325 2525) $PN 25_29
J 0
(-8315 2535);
DISPLAY 0.617021 (-8315 2535);
PAINT MONO (-8315 2535);
FORCEPROP 2 LASTPIN (-8325 2475) $PN 30
J 0
(-8315 2485);
DISPLAY 0.617021 (-8315 2485);
PAINT MONO (-8315 2485);
FORCEPROP 2 LASTPIN (-8325 1625) $PN 1
J 0
(-8315 1635);
DISPLAY 0.617021 (-8315 1635);
PAINT MONO (-8315 1635);
FORCEPROP 2 LAST CDS_LIB pure_quanta
J 0
(-8725 1875);
DISPLAY INVISIBLE (-8725 1875);
FORCEPROP 1 LAST CDS_LMAN_SYM_OUTLINE -300,700,250,-650
J 0
(-8725 1875);
DISPLAY 0.468085 (-8725 1875);
PAINT GREEN (-8725 1875);
DISPLAY INVISIBLE (-8725 1875);
FORCEPROP 1 LAST NEEDS_NO_SIZE TRUE
J 0
(-8725 1875);
DISPLAY 0.723404 (-8725 1875);
PAINT GREEN (-8725 1875);
DISPLAY INVISIBLE (-8725 1875);
FORCEPROP 1 LAST PATH I9
J 0
(-8725 1875);
DISPLAY 0.723404 (-8725 1875);
PAINT GREEN (-8725 1875);
DISPLAY INVISIBLE (-8725 1875);
FORCEPROP 2 LAST $SEC 1
J 0
(-9025 2800);
DISPLAY 0.680851 (-9025 2800);
PAINT MONO (-9025 2800);
DISPLAY INVISIBLE (-9025 2800);
FORCEPROP 2 LAST CDS_SEC 1
J 0
(-8975 2875);
DISPLAY 1.021277 (-8975 2875);
DISPLAY INVISIBLE (-8975 2875);
FORCEADD QUANTA_TITLE_BLOCK_C..1
(-2250 525);
FORCEPROP 0 LAST CDS_CON_LAST_MODIFIED Fri Aug 25 14:05:00 2023
J 0
(-4135 540);
DISPLAY INVISIBLE (-4135 540);
FORCEPROP 1 LAST CUSTOM_TXT_CDS <CON_LAST_MODIFIED>
J 0
(-4135 540);
DISPLAY 0.978723 (-4135 540);
FORCEPROP 2 LAST CUSTOM_TXT_CDS <XR_PAGE_TITLE>
J 0
(-10140 5775);
DISPLAY 0.638298 (-10140 5775);
PAINT PINK (-10140 5775);
DISPLAY INVISIBLE (-10140 5775);
FORCEPROP 1 LAST CUSTOM_TXT_CDS <NAME_2>
J 0
(-5425 575);
FORCEPROP 1 LAST CUSTOM_TXT_CDS <NAME_1>
J 0
(-5425 700);
FORCEPROP 1 LAST CUSTOM_TXT_CDS <Q_NUMBER>
J 0
(-3653 628);
DISPLAY 1.212766 (-3653 628);
FORCEPROP 1 LAST CUSTOM_TXT_CDS <Q_PROJ>
J 0
(-4632 627);
DISPLAY 1.212766 (-4632 627);
FORCEPROP 1 LAST CUSTOM_TXT_CDS <Q_REV>
J 0
(-2434 628);
DISPLAY 1.212766 (-2434 628);
FORCEPROP 1 LAST CUSTOM_TXT_CDS <CON_PAGE_NUM> OF <CON_TOTAL_PAGES>
J 0
(-2696 543);
DISPLAY 0.978723 (-2696 543);
FORCEPROP 1 LAST Q_TITLE VCCFA_EHV_FIVRA CPU1 VR PHASE 1&2(6/7)
J 0
(-11550 575);
DISPLAY 2.446809 (-11550 575);
PAINT GREEN (-11550 575);
FORCEPROP 1 LAST Q_DEPT 
J 1
(-6013 574);
DISPLAY 1.957447 (-6013 574);
PAINT GREEN (-6013 574);
FORCEPROP 2 LAST CDS_XR_PAGE_TITLE CR-289 : @S9S_MB_2U_LIB.S9S_MB_2U(SCH_1):PAGE289
J 0
(-10140 5775);
DISPLAY 0.638298 (-10140 5775);
PAINT PINK (-10140 5775);
DISPLAY INVISIBLE (-10140 5775);
FORCEPROP 2 LAST PAGE_BORDER TRUE
J 0
(-10140 5775);
DISPLAY 0.638298 (-10140 5775);
PAINT PINK (-10140 5775);
DISPLAY INVISIBLE (-10140 5775);
FORCEPROP 1 LAST CDS_LMAN_SYM_OUTLINE -9475,6775,100,-125
J 0
(-2250 525);
DISPLAY 0.468085 (-2250 525);
PAINT GREEN (-2250 525);
DISPLAY INVISIBLE (-2250 525);
FORCEPROP 2 LAST CDS_LIB pure_quanta
J 0
(-2250 525);
DISPLAY INVISIBLE (-2250 525);
FORCEPROP 1 LAST COMMENT_BODY TRUE
J 0
(-2238 512);
DISPLAY 0.978723 (-2238 512);
PAINT GREEN (-2238 512);
DISPLAY INVISIBLE (-2238 512);
FORCEADD DNS..1
(-10750 1350);
PAINT RED (-10750 1350);
FORCEPROP 1 LAST COMMENT_BODY TRUE
R 1
J 0
(-10675 1125);
DISPLAY 0.872340 (-10675 1125);
PAINT GREEN (-10675 1125);
DISPLAY INVISIBLE (-10675 1125);
FORCEPROP 2 LAST CDS_LIB mstr_misc
J 0
(-10750 1350);
PAINT MONO (-10750 1350);
DISPLAY INVISIBLE (-10750 1350);
FORCEADD DNS..1
(-10075 3350);
PAINT RED (-10075 3350);
FORCEPROP 1 LAST COMMENT_BODY TRUE
R 1
J 0
(-10000 3125);
DISPLAY 0.872340 (-10000 3125);
PAINT GREEN (-10000 3125);
DISPLAY INVISIBLE (-10000 3125);
FORCEPROP 2 LAST CDS_LIB mstr_misc
J 0
(-10075 3350);
DISPLAY INVISIBLE (-10075 3350);
FORCEADD DNS..1
(-10725 4150);
PAINT RED (-10725 4150);
FORCEPROP 1 LAST COMMENT_BODY TRUE
R 1
J 0
(-10650 3925);
DISPLAY 0.872340 (-10650 3925);
PAINT GREEN (-10650 3925);
DISPLAY INVISIBLE (-10650 3925);
FORCEPROP 2 LAST CDS_LIB mstr_misc
J 0
(-10725 4150);
PAINT MONO (-10725 4150);
DISPLAY INVISIBLE (-10725 4150);
FORCEADD DNS..1
(-10075 6150);
PAINT RED (-10075 6150);
FORCEPROP 1 LAST COMMENT_BODY TRUE
R 1
J 0
(-10000 5925);
DISPLAY 0.872340 (-10000 5925);
PAINT GREEN (-10000 5925);
DISPLAY INVISIBLE (-10000 5925);
FORCEPROP 2 LAST CDS_LIB mstr_misc
J 0
(-10075 6150);
DISPLAY INVISIBLE (-10075 6150);
WIRE 16 -1 (-10775 3550)(-10775 3475);
WIRE 16 -1 (-10125 3550)(-10125 3475);
WIRE 16 -1 (-10775 6350)(-10775 6275);
WIRE 16 -1 (-10125 6350)(-10125 6275);
WIRE 16 -1 (-6125 3100)(-6125 3025);
WIRE 16 -1 (-6125 5900)(-6125 5825);
WIRE 16 -1 (-3300 1950)(-3300 1875);
WIRE 16 -1 (-2825 3075)(-2825 3025);
WIRE 16 -1 (-5000 5675)(-5000 5550);
WIRE 16 -1 (-3825 4825)(-3825 4675);
WIRE 16 -1 (-2975 5650)(-2975 5550);
WIRE 16 -1 (-10750 1275)(-10750 1200);
WIRE 16 -1 (-10800 1675)(-10800 1650);
WIRE 16 -1 (-10800 1675)(-10075 1675);
WIRE 16 -1 (-10250 2225)(-10250 2125);
WIRE 16 -1 (-9725 2625)(-9725 2525);
WIRE 16 -1 (-10725 4075)(-10725 4000);
WIRE 16 -1 (-10800 4475)(-10800 4450);
WIRE 16 -1 (-10800 4475)(-10075 4475);
WIRE 16 -1 (-10250 5025)(-10250 4925);
WIRE 16 -1 (-9725 5425)(-9725 5325);
WIRE 16 -1 (-8075 1275)(-8075 1200);
WIRE 16 -1 (-8075 1325)(-8075 1275);
WIRE 16 -1 (-8325 1275)(-8075 1275);
WIRE 16 -1 (-6125 2450)(-6125 2525);
WIRE 16 -1 (-8075 4075)(-8075 4000);
WIRE 16 -1 (-8075 4125)(-8075 4075);
WIRE 16 -1 (-8325 4075)(-8075 4075);
WIRE 16 -1 (-6125 5250)(-6125 5325);
WIRE 16 -1 (-3300 1375)(-3300 1450);
WIRE 16 -1 (-2825 2600)(-2825 2500);
WIRE 16 -1 (-3275 2600)(-2825 2600);
WIRE 16 -1 (-2825 2700)(-2825 2600);
WIRE 16 -1 (-5000 5150)(-5000 5250);
WIRE 16 -1 (-3825 4150)(-3825 4250);
WIRE 16 -1 (-3125 5125)(-3125 5075);
WIRE 16 -1 (-3400 5125)(-3125 5125);
WIRE 16 -1 (-3125 5225)(-3125 5125);
WIRE 16 -1 (-3275 2700)(-3275 2600);
WIRE 16 -1 (-3775 2700)(-3775 2600);
WIRE 16 -1 (-3275 2600)(-3775 2600);
WIRE 16 -1 (-4300 2600)(-4300 2700);
WIRE 16 -1 (-4300 2600)(-3775 2600);
WIRE 16 -1 (-4825 2600)(-4300 2600);
WIRE 16 -1 (-4825 2700)(-4825 2600);
WIRE 16 -1 (-2825 3025)(-2825 2900);
WIRE 16 -1 (-3275 2900)(-3275 3025);
WIRE 16 -1 (-3275 3025)(-2825 3025);
WIRE 16 -1 (-3775 2900)(-3775 3025);
WIRE 16 -1 (-3275 3025)(-3775 3025);
WIRE 16 -1 (-4300 3025)(-4300 2900);
WIRE 16 -1 (-4300 3025)(-3775 3025);
WIRE 16 -1 (-4825 3025)(-4300 3025);
WIRE 16 -1 (-4825 2900)(-4825 3025);
WIRE 16 -1 (-3400 5225)(-3400 5125);
WIRE 16 -1 (-3675 5225)(-3675 5125);
WIRE 16 -1 (-3675 5125)(-3400 5125);
WIRE 16 -1 (-3950 5225)(-3950 5125);
WIRE 16 -1 (-3950 5125)(-3675 5125);
WIRE 16 -1 (-4250 5125)(-3950 5125);
WIRE 16 -1 (-4250 5225)(-4250 5125);
WIRE 16 -1 (-3125 5550)(-3125 5425);
WIRE 16 -1 (-2975 5550)(-3125 5550);
WIRE 16 -1 (-3400 5425)(-3400 5550);
WIRE 16 -1 (-3400 5550)(-3125 5550);
WIRE 16 -1 (-3675 5425)(-3675 5550);
WIRE 16 -1 (-3675 5550)(-3400 5550);
WIRE 16 -1 (-3950 5425)(-3950 5550);
WIRE 16 -1 (-3950 5550)(-3675 5550);
WIRE 16 -1 (-4250 5425)(-4250 5550);
WIRE 16 -1 (-4250 5550)(-3950 5550);
WIRE 16 -1 (-4475 5550)(-4250 5550);
WIRE 16 -1 (-5750 4425)(-5925 4425);
WIRE 16 -1 (-4125 4575)(-4125 4675);
WIRE 16 -1 (-3825 4675)(-4125 4675);
WIRE 16 -1 (-5750 4675)(-5750 4425);
WIRE 16 -1 (-5750 4675)(-5925 4675);
WIRE 16 -1 (-5050 4675)(-5750 4675);
WIRE 16 -1 (-5050 4575)(-5050 4675);
WIRE 16 -1 (-4550 4675)(-4550 4575);
WIRE 16 -1 (-4550 4675)(-4125 4675);
WIRE 16 -1 (-4550 4675)(-5050 4675);
WIRE 16 -1 (-4125 4375)(-4125 4250);
WIRE 16 -1 (-3825 4250)(-4125 4250);
WIRE 16 -1 (-4550 4250)(-4550 4375);
WIRE 16 -1 (-4125 4250)(-4550 4250);
WIRE 16 -1 (-4550 4250)(-5050 4250);
WIRE 16 -1 (-5050 4375)(-5050 4250);
WIRE 16 -1 (-5000 5550)(-4675 5550);
WIRE 16 -1 (-5000 5450)(-5000 5550);
WIRE 16 -1 (-3650 1875)(-3650 1775);
WIRE 16 -1 (-3300 1875)(-3650 1875);
WIRE 16 -1 (-4125 1775)(-4125 1875);
WIRE 16 -1 (-3650 1875)(-4125 1875);
WIRE 16 -1 (-5750 1625)(-5925 1625);
WIRE 16 -1 (-4550 1875)(-4550 1775);
WIRE 16 -1 (-4550 1875)(-4125 1875);
WIRE 16 -1 (-4975 1775)(-4975 1875);
WIRE 16 -1 (-4975 1875)(-4550 1875);
WIRE 16 -1 (-5925 1875)(-5750 1875);
WIRE 16 -1 (-5750 1875)(-5750 1625);
WIRE 16 -1 (-5750 1875)(-4975 1875);
WIRE 16 -1 (-3650 1575)(-3650 1450);
WIRE 16 -1 (-3300 1450)(-3650 1450);
WIRE 16 -1 (-4125 1575)(-4125 1450);
WIRE 16 -1 (-3650 1450)(-4125 1450);
WIRE 16 -1 (-4125 1450)(-4550 1450);
WIRE 16 -1 (-4550 1450)(-4550 1575);
WIRE 16 -1 (-4975 1450)(-4550 1450);
WIRE 16 -1 (-4975 1575)(-4975 1450);
WIRE 16 -1 (-6275 5675)(-6275 5825);
WIRE 16 -1 (-6125 5825)(-6275 5825);
WIRE 16 -1 (-6725 5675)(-6725 5825);
WIRE 16 -1 (-6275 5825)(-6725 5825);
WIRE 16 -1 (-7125 5825)(-7125 5675);
WIRE 16 -1 (-7125 5825)(-6725 5825);
WIRE 16 -1 (-8150 5275)(-8325 5275);
WIRE 16 -1 (-8325 5325)(-8150 5325);
WIRE 16 -1 (-8150 5325)(-8150 5275);
WIRE 16 -1 (-7525 5675)(-7525 5825);
WIRE 16 -1 (-7525 5825)(-7125 5825);
WIRE 16 -1 (-7925 5675)(-7925 5825);
WIRE 16 -1 (-7925 5825)(-7525 5825);
WIRE 16 -1 (-8150 5825)(-8150 5325);
WIRE 16 -1 (-8150 5825)(-7925 5825);
WIRE 16 -1 (-6275 5475)(-6275 5325);
WIRE 16 -1 (-6125 5325)(-6275 5325);
WIRE 16 -1 (-6725 5475)(-6725 5325);
WIRE 16 -1 (-6275 5325)(-6725 5325);
WIRE 16 -1 (-7125 5475)(-7125 5325);
WIRE 16 -1 (-7125 5325)(-6725 5325);
WIRE 16 -1 (-7525 5475)(-7525 5325);
WIRE 16 -1 (-7125 5325)(-7525 5325);
WIRE 16 -1 (-7925 5325)(-7525 5325);
WIRE 16 -1 (-7925 5475)(-7925 5325);
WIRE 16 -1 (-6300 4775)(-6300 4850);
WIRE 16 -1 (-8325 4775)(-6300 4775);
FORCEPROP 2 LAST SIG_NAME SW_PVCCFA_EHV_FIVRA_CPU1_BOOTR1
J 0
(-8135 4785);
DISPLAY 0.617021 (-8135 4785);
WIRE 16 -1 (-8325 4675)(-6125 4675);
FORCEPROP 2 LAST SIG_NAME SW_PVCCFA_EHV_FIVRA_CPU1_SW1
J 0
(-8135 4685);
DISPLAY 0.617021 (-8135 4685);
WIRE 16 -1 (-8325 4425)(-6125 4425);
FORCEPROP 2 LAST SIG_NAME PVCCFA_EHV_FIVRA_CPU1_VOS1
J 0
(-8135 4435);
DISPLAY 0.617021 (-8135 4435);
WIRE 16 -1 (-6300 5125)(-6300 5050);
WIRE 16 -1 (-7125 5125)(-6300 5125);
FORCEPROP 2 LAST SIG_NAME SW_PVCCFA_EHV_FIVRA_CPU1_BOOT1_R
J 0
(-6935 5135);
DISPLAY 0.617021 (-6935 5135);
WIRE 16 -1 (-8325 4125)(-8075 4125);
WIRE 16 -1 (-8075 4225)(-8325 4225);
WIRE 16 -1 (-8325 4175)(-8075 4175);
WIRE 16 -1 (-8075 4175)(-8075 4125);
WIRE 16 -1 (-8075 4175)(-8075 4225);
WIRE 16 -1 (-8175 5125)(-7325 5125);
WIRE 16 -1 (-8175 5025)(-8175 5125);
FORCEPROP 2 LAST SIG_NAME SW_PVCCFA_EHV_FIVRA_CPU1_BOOT1
J 0
(-8385 5135);
DISPLAY 0.617021 (-8385 5135);
WIRE 16 -1 (-8325 5025)(-8175 5025);
WIRE 16 -1 (-6275 2875)(-6275 3025);
WIRE 16 -1 (-6125 3025)(-6275 3025);
WIRE 16 -1 (-6725 2875)(-6725 3025);
WIRE 16 -1 (-6275 3025)(-6725 3025);
WIRE 16 -1 (-7125 3025)(-7125 2875);
WIRE 16 -1 (-7125 3025)(-6725 3025);
WIRE 16 -1 (-8150 2475)(-8325 2475);
WIRE 16 -1 (-8325 2525)(-8150 2525);
WIRE 16 -1 (-8150 2525)(-8150 2475);
WIRE 16 -1 (-7525 2875)(-7525 3025);
WIRE 16 -1 (-7525 3025)(-7125 3025);
WIRE 16 -1 (-7925 2875)(-7925 3025);
WIRE 16 -1 (-7925 3025)(-7525 3025);
WIRE 16 -1 (-8150 3025)(-8150 2525);
WIRE 16 -1 (-8150 3025)(-7925 3025);
WIRE 16 -1 (-6275 2675)(-6275 2525);
WIRE 16 -1 (-6125 2525)(-6275 2525);
WIRE 16 -1 (-6725 2675)(-6725 2525);
WIRE 16 -1 (-6275 2525)(-6725 2525);
WIRE 16 -1 (-7125 2525)(-6725 2525);
WIRE 16 -1 (-7125 2675)(-7125 2525);
WIRE 16 -1 (-7525 2675)(-7525 2525);
WIRE 16 -1 (-7125 2525)(-7525 2525);
WIRE 16 -1 (-7925 2525)(-7525 2525);
WIRE 16 -1 (-7925 2675)(-7925 2525);
WIRE 16 -1 (-8325 1875)(-6125 1875);
FORCEPROP 2 LAST SIG_NAME SW_PVCCFA_EHV_FIVRA_CPU1_SW2
J 0
(-8135 1885);
DISPLAY 0.617021 (-8135 1885);
WIRE 16 -1 (-6300 1975)(-6300 2050);
WIRE 16 -1 (-8325 1975)(-6300 1975);
FORCEPROP 2 LAST SIG_NAME SW_PVCCFA_EHV_FIVRA_CPU1_BOOTR2
J 0
(-8135 1985);
DISPLAY 0.617021 (-8135 1985);
WIRE 16 -1 (-6300 2325)(-6300 2250);
WIRE 16 -1 (-7125 2325)(-6300 2325);
FORCEPROP 2 LAST SIG_NAME SW_PVCCFA_EHV_FIVRA_CPU1_BOOT2_R
J 0
(-6935 2335);
DISPLAY 0.617021 (-6935 2335);
WIRE 16 -1 (-8325 1625)(-6125 1625);
FORCEPROP 2 LAST SIG_NAME PVCCFA_EHV_FIVRA_CPU1_VOS2
J 0
(-8135 1635);
DISPLAY 0.617021 (-8135 1635);
WIRE 16 -1 (-8175 2325)(-7325 2325);
WIRE 16 -1 (-8175 2225)(-8175 2325);
FORCEPROP 2 LAST SIG_NAME SW_PVCCFA_EHV_FIVRA_CPU1_BOOT2
J 0
(-8385 2335);
DISPLAY 0.617021 (-8385 2335);
WIRE 16 -1 (-8325 2225)(-8175 2225);
WIRE 16 -1 (-8325 1325)(-8075 1325);
WIRE 16 -1 (-8075 1425)(-8325 1425);
WIRE 16 -1 (-8325 1375)(-8075 1375);
WIRE 16 -1 (-8075 1375)(-8075 1325);
WIRE 16 -1 (-8075 1375)(-8075 1425);
WIRE 16 -1 (-9325 5325)(-9175 5325);
WIRE 16 -1 (-9325 5325)(-9325 5725);
WIRE 16 -1 (-9725 5625)(-9725 5725);
WIRE 16 -1 (-9325 5725)(-9725 5725);
WIRE 16 -1 (-10125 6075)(-10125 5725);
WIRE 16 -1 (-9725 5725)(-10125 5725);
WIRE 16 -1 (-10250 5725)(-10250 5625);
WIRE 16 -1 (-10125 5725)(-10250 5725);
WIRE 16 -1 (-10775 5725)(-10250 5725);
FORCEPROP 2 LAST SIG_NAME PVCCFA_EHV_FIVRA_CPU1_PVCC1
J 0
(-10085 5735);
DISPLAY 0.617021 (-10085 5735);
WIRE 16 -1 (-10775 6075)(-10775 5725);
WIRE 16 -1 (-9175 4825)(-9325 4825);
WIRE 16 -1 (-9325 5025)(-9325 4825);
WIRE 16 -1 (-9175 5025)(-9325 5025);
WIRE 16 -1 (-9325 5025)(-10000 5025);
FORCEPROP 0 LAST CDS_PHYS_NET_NAME PVCCFA_EHV_FIVRA_CPU1_VDD1
J 0
(-9935 5065);
PAINT MONO (-9935 5065);
DISPLAY INVISIBLE (-9935 5065);
FORCEPROP 2 LAST SIG_NAME PVCCFA_EHV_FIVRA_CPU1_VDD1
J 0
(-9960 5035);
DISPLAY 0.617021 (-9960 5035);
WIRE 16 -1 (-10000 5025)(-10000 5325);
WIRE 16 -1 (-10250 5325)(-10250 5425);
WIRE 16 -1 (-10000 5325)(-10250 5325);
WIRE 16 -1 (-10250 5225)(-10250 5325);
WIRE 16 -1 (-9325 4475)(-9875 4475);
WIRE 16 -1 (-10200 4575)(-9325 4575);
FORCEPROP 2 LAST SIG_NAME PVCCIN_CPU1_VREF
J 0
(-10135 4585);
DISPLAY 0.617021 (-10135 4585);
WIRE 16 -1 (-9325 4575)(-9325 4475);
FORCEPROP 0 LAST CDS_PHYS_NET_NAME PVCCIN_CPU1_VREF
J 0
(-9325 4500);
PAINT MONO (-9325 4500);
DISPLAY INVISIBLE (-9325 4500);
WIRE 16 -1 (-9325 4575)(-9175 4575);
WIRE 16 -1 (-9175 4175)(-10200 4175);
FORCEPROP 2 LAST SIG_NAME PVCCFA_EHV_FIVRA_CPU1_BTSEN
J 0
(-10135 4185);
DISPLAY 0.617021 (-10135 4185);
WIRE 16 -1 (-9175 4075)(-10200 4075);
FORCEPROP 2 LAST SIG_NAME PVCCFA_EHV_FIVRA_CPU1_PWM1
J 0
(-10135 4085);
DISPLAY 0.617021 (-10135 4085);
WIRE 16 -1 (-9175 4675)(-10200 4675);
FORCEPROP 2 LAST SIG_NAME PVCCFA_EHV_FIVRA_CPU1_IMON1
J 0
(-10135 4685);
DISPLAY 0.617021 (-10135 4685);
WIRE 16 -1 (-10725 4375)(-10725 4275);
WIRE 16 -1 (-10725 4375)(-9175 4375);
FORCEPROP 2 LAST SIG_NAME PVCCFA_EHV_FIVRA_CPU1_LSET1
J 0
(-10135 4385);
DISPLAY 0.617021 (-10135 4385);
WIRE 16 -1 (-9325 2525)(-9175 2525);
WIRE 16 -1 (-9325 2525)(-9325 2925);
WIRE 16 -1 (-9725 2825)(-9725 2925);
WIRE 16 -1 (-9325 2925)(-9725 2925);
WIRE 16 -1 (-9725 2925)(-10125 2925);
FORCEPROP 2 LAST SIG_NAME PVCCFA_EHV_FIVRA_CPU1_PVCC2
J 0
(-10110 2935);
DISPLAY 0.617021 (-10110 2935);
WIRE 16 -1 (-10125 3275)(-10125 2925);
WIRE 16 -1 (-10250 2925)(-10250 2825);
WIRE 16 -1 (-10125 2925)(-10250 2925);
WIRE 16 -1 (-10775 2925)(-10250 2925);
WIRE 16 -1 (-10775 3275)(-10775 2925);
WIRE 16 -1 (-9175 2025)(-9325 2025);
WIRE 16 -1 (-9325 2225)(-9325 2025);
WIRE 16 -1 (-9175 2225)(-9325 2225);
WIRE 16 -1 (-9325 2225)(-10000 2225);
FORCEPROP 0 LAST CDS_PHYS_NET_NAME PVCCFA_EHV_FIVRA_CPU1_VDD2
J 0
(-9935 2265);
PAINT MONO (-9935 2265);
DISPLAY INVISIBLE (-9935 2265);
FORCEPROP 2 LAST SIG_NAME PVCCFA_EHV_FIVRA_CPU1_VDD2
J 0
(-9960 2235);
DISPLAY 0.617021 (-9960 2235);
WIRE 16 -1 (-10000 2225)(-10000 2525);
WIRE 16 -1 (-10250 2525)(-10250 2625);
WIRE 16 -1 (-10000 2525)(-10250 2525);
WIRE 16 -1 (-10250 2425)(-10250 2525);
WIRE 16 -1 (-9175 1875)(-10225 1875);
FORCEPROP 2 LAST SIG_NAME PVCCFA_EHV_FIVRA_CPU1_IMON2
J 0
(-10160 1885);
DISPLAY 0.617021 (-10160 1885);
WIRE 16 -1 (-9325 1675)(-9875 1675);
WIRE 16 -1 (-10225 1775)(-9325 1775);
FORCEPROP 2 LAST SIG_NAME PVCCIN_CPU1_VREF
J 0
(-10160 1785);
DISPLAY 0.617021 (-10160 1785);
WIRE 16 -1 (-9325 1775)(-9325 1675);
FORCEPROP 0 LAST CDS_PHYS_NET_NAME PVCCIN_CPU1_VREF
J 0
(-9325 1700);
PAINT MONO (-9325 1700);
DISPLAY INVISIBLE (-9325 1700);
WIRE 16 -1 (-9325 1775)(-9175 1775);
WIRE 16 -1 (-9175 1275)(-10225 1275);
FORCEPROP 2 LAST SIG_NAME PVCCFA_EHV_FIVRA_CPU1_PWM2
J 0
(-10160 1285);
DISPLAY 0.617021 (-10160 1285);
WIRE 16 -1 (-9175 1375)(-10225 1375);
FORCEPROP 2 LAST SIG_NAME PVCCFA_EHV_FIVRA_CPU1_BTSEN
J 0
(-10160 1385);
DISPLAY 0.617021 (-10160 1385);
WIRE 16 -1 (-10750 1575)(-10750 1475);
WIRE 16 -1 (-10750 1575)(-9175 1575);
FORCEPROP 2 LAST SIG_NAME PVCCFA_EHV_FIVRA_CPU1_LSET2
J 0
(-10160 1585);
DISPLAY 0.617021 (-10160 1585);
DOT 1 (-9325 1775);
DOT 1 (-10250 2525);
DOT 1 (-10250 2925);
DOT 1 (-9325 2225);
DOT 1 (-10125 2925);
DOT 1 (-9725 2925);
DOT 1 (-10250 5325);
DOT 1 (-10250 5725);
DOT 1 (-9325 4575);
DOT 1 (-10125 5725);
DOT 1 (-9725 5725);
DOT 1 (-9325 5025);
DOT 1 (-8075 1275);
DOT 1 (-8075 1325);
DOT 1 (-8075 1375);
DOT 1 (-8150 2525);
DOT 1 (-7525 2525);
DOT 1 (-7125 2525);
DOT 1 (-7925 3025);
DOT 1 (-7525 3025);
DOT 1 (-7125 3025);
DOT 1 (-6725 2525);
DOT 1 (-6275 2525);
DOT 1 (-6725 3025);
DOT 1 (-6275 3025);
DOT 1 (-5750 1875);
DOT 1 (-8150 5325);
DOT 1 (-8075 4075);
DOT 1 (-8075 4125);
DOT 1 (-8075 4175);
DOT 1 (-7925 5825);
DOT 1 (-7525 5325);
DOT 1 (-7125 5325);
DOT 1 (-7525 5825);
DOT 1 (-7125 5825);
DOT 1 (-6725 5325);
DOT 1 (-6725 5825);
DOT 1 (-6275 5325);
DOT 1 (-6275 5825);
DOT 1 (-5750 4675);
DOT 1 (-5050 4675);
DOT 1 (-4550 1450);
DOT 1 (-4125 1450);
DOT 1 (-3650 1450);
DOT 1 (-4975 1875);
DOT 1 (-4550 1875);
DOT 1 (-4125 1875);
DOT 1 (-4300 2600);
DOT 1 (-4300 3025);
DOT 1 (-3650 1875);
DOT 1 (-3775 2600);
DOT 1 (-3275 2600);
DOT 1 (-3775 3025);
DOT 1 (-3275 3025);
DOT 1 (-2825 2600);
DOT 1 (-2825 3025);
DOT 1 (-4550 4250);
DOT 1 (-4550 4675);
DOT 1 (-4125 4250);
DOT 1 (-4125 4675);
DOT 1 (-5000 5550);
DOT 1 (-4250 5550);
DOT 1 (-3950 5125);
DOT 1 (-3675 5125);
DOT 1 (-3950 5550);
DOT 1 (-3675 5550);
DOT 1 (-3400 5125);
DOT 1 (-3125 5125);
DOT 1 (-3400 5550);
DOT 1 (-3125 5550);
FORCENOTE
20211013 MODIFY FOR GT
(-11500 7000) 0;
DISPLAY LEFT (-11500 7000);
DISPLAY 1.595745 (-11500 7000);
PAINT PINK (-11500 7000);
FORCENOTE
PVCCFA_EHV_FIVRA_CPU1_PHASE1
(-9425 5900) 0;
DISPLAY LEFT (-9425 5900);
DISPLAY 1.021277 (-9425 5900);
PAINT WHITE (-9425 5900);
FORCENOTE
PVCCFA_EHV_FIVRA_CPU1_PHASE2
(-9450 3100) 0;
DISPLAY LEFT (-9450 3100);
DISPLAY 1.021277 (-9450 3100);
PAINT WHITE (-9450 3100);
FORCENOTE
10.0*7.5*12.0
(-5700 2150) 0;
DISPLAY LEFT (-5700 2150);
DISPLAY 1.021277 (-5700 2150);
FORCENOTE
PG2323.131HLT
(-5700 2225) 0;
DISPLAY LEFT (-5700 2225);
DISPLAY 1.021277 (-5700 2225);
FORCENOTE
PG2323.131HLT
(-5750 5000) 0;
DISPLAY LEFT (-5750 5000);
DISPLAY 1.021277 (-5750 5000);
FORCENOTE
10.0*7.5*12.0
(-5750 4925) 0;
DISPLAY LEFT (-5750 4925);
DISPLAY 1.021277 (-5750 4925);
FORCENOTE
DCR = 0.103M OHM
(-5700 2000) 0;
DISPLAY LEFT (-5700 2000);
DISPLAY 1.021277 (-5700 2000);
FORCENOTE
ISAT = 90A @ 100C
(-5750 4850) 0;
DISPLAY LEFT (-5750 4850);
DISPLAY 1.021277 (-5750 4850);
FORCENOTE
ISAT = 90A @ 100C
(-5700 2075) 0;
DISPLAY LEFT (-5700 2075);
DISPLAY 1.021277 (-5700 2075);
FORCENOTE
DCR = 0.103M OHM
(-5750 4775) 0;
DISPLAY LEFT (-5750 4775);
DISPLAY 1.021277 (-5750 4775);
FORCENOTE
APPLY TO ALL RAILS.
(-4375 1000) 0;
DISPLAY LEFT (-4375 1000);
DISPLAY 1.021277 (-4375 1000);
FORCENOTE
(499OHM) TO ABSORB LEAKAGE FROM SPS.
(-4375 1075) 0;
DISPLAY LEFT (-4375 1075);
DISPLAY 1.021277 (-4375 1075);
FORCENOTE
RENESAS RECOMMEND BLEEDER RESISTOR
(-4375 1150) 0;
DISPLAY LEFT (-4375 1150);
DISPLAY 1.021277 (-4375 1150);
FORCENOTE
4.5*4.5*4.5
(-4400 5800) 0;
DISPLAY LEFT (-4400 5800);
DISPLAY 0.808511 (-4400 5800);
FORCENOTE
DCR = 0.12M OHM
(-4400 5650) 0;
DISPLAY LEFT (-4400 5650);
DISPLAY 0.808511 (-4400 5650);
FORCENOTE
ISAT = 13A @ 100C
(-4400 5725) 0;
DISPLAY LEFT (-4400 5725);
DISPLAY 0.808511 (-4400 5725);
FORCENOTE
HCBS4545-101
(-4400 5875) 0;
DISPLAY LEFT (-4400 5875);
DISPLAY 0.808511 (-4400 5875);
FORCENOTE
ESR=9.5M OHM
(-3075 5100) 0;
DISPLAY LEFT (-3075 5100);
DISPLAY 0.638298 (-3075 5100);
QUIT
